G04 ================== begin FILE IDENTIFICATION RECORD ==================*
G04 Layout Name:  9052_F0T_PDB_Converter_Brick_F_V03_1208_1600.brd*
G04 Film Name:    gnd3*
G04 File Format:  Gerber RS274X*
G04 File Origin:  Cadence Allegro 17.2-S081*
G04 Origin Date:  Wed Dec 21 09:54:59 2022*
G04 *
G04 Layer:  DRAWING FORMAT/TITLE_BLOCK_A*
G04 Layer:  PIN/SPECIAL_DRILL*
G04 Layer:  DRAWING FORMAT/TITLE_BLOCK*
G04 Layer:  VIA CLASS/GND3*
G04 Layer:  PIN/GND3*
G04 Layer:  MANUFACTURING/PHOTOPLOT_OUTLINE*
G04 Layer:  ETCH/GND3*
G04 Layer:  DRAWING FORMAT/TITLE_DATA_GND3*
G04 *
G04 Offset:    (0.00 0.00)*
G04 Mirror:    No*
G04 Mode:      Negative*
G04 Rotation:  0*
G04 FullContactRelief:  No*
G04 UndefLineWidth:     6.00*
G04 ================== end FILE IDENTIFICATION RECORD ====================*
%FSLAX25Y25*MOIN*%
%IR0*IPPOS*OFA0.00000B0.00000*MIA0B0*SFA1.00000B1.00000*%
%ADD20C,.03*%
%AMMACRO12*
4,1,41,.45275,-.05906,
.463006,-.058163,
.47295,-.055498,
.48228,-.051147,
.490713,-.045243,
.497993,-.037963,
.503897,-.02953,
.508248,-.0202,
.510913,-.010256,
.51181,0.0,
.510913,.010256,
.508248,.0202,
.503897,.02953,
.497993,.037963,
.490713,.045243,
.48228,.051147,
.47295,.055498,
.463006,.058163,
.45275,.05906,
.33464,.05906,
-.4082,.09829,
-.425347,.097699,
-.442131,.09414,
-.458041,.08772,
-.472595,.078635,
-.485351,.06716,
-.49592,.053645,
-.503981,.0385,
-.509291,.022185,
-.511686,.005196,
-.511095,-.011951,
-.507536,-.028734,
-.501116,-.044645,
-.492031,-.059199,
-.480557,-.071954,
-.467041,-.082523,
-.451896,-.090585,
-.435582,-.095894,
-.418593,-.09829,
-.4082,-.09829,
.33464,-.05906,
.45275,-.05906,
0.0*
%
%ADD12MACRO12*%
%ADD35C,.06*%
%ADD16C,.061*%
%ADD28C,.062*%
%ADD25C,.026*%
%ADD17C,.054*%
%AMMACRO27*
4,1,36,.0025,0.0,
.002462,.000434,
.002349,.000855,
.002165,.00125,
.001915,.001607,
.001607,.001915,
.00125,.002165,
.000855,.002349,
.000434,.002462,
0.0,.0025,
-.000434,.002462,
-.000855,.002349,
-.00125,.002165,
-.001607,.001915,
-.001915,.001607,
-.002165,.00125,
-.002349,.000855,
-.002462,.000434,
-.0025,0.0,
-.002462,-.000434,
-.002349,-.000855,
-.002165,-.00125,
-.001915,-.001607,
-.001607,-.001915,
-.00125,-.002165,
-.000855,-.002349,
-.000434,-.002462,
0.0,-.0025,
.000434,-.002462,
.000855,-.002349,
.00125,-.002165,
.001607,-.001915,
.001915,-.001607,
.002165,-.00125,
.002349,-.000855,
.002462,-.000434,
.0025,0.0,
180.*
%
%ADD27MACRO27*%
%AMMACRO23*
4,1,36,.0025,0.0,
.002462,.000434,
.002349,.000855,
.002165,.00125,
.001915,.001607,
.001607,.001915,
.00125,.002165,
.000855,.002349,
.000434,.002462,
0.0,.0025,
-.000434,.002462,
-.000855,.002349,
-.00125,.002165,
-.001607,.001915,
-.001915,.001607,
-.002165,.00125,
-.002349,.000855,
-.002462,.000434,
-.0025,0.0,
-.002462,-.000434,
-.002349,-.000855,
-.002165,-.00125,
-.001915,-.001607,
-.001607,-.001915,
-.00125,-.002165,
-.000855,-.002349,
-.000434,-.002462,
0.0,-.0025,
.000434,-.002462,
.000855,-.002349,
.00125,-.002165,
.001607,-.001915,
.001915,-.001607,
.002165,-.00125,
.002349,-.000855,
.002462,-.000434,
.0025,0.0,
270.*
%
%ADD23MACRO23*%
%ADD33C,.083*%
%ADD30C,.056*%
%ADD43C,.066*%
%ADD38C,.06015*%
%ADD40C,.087*%
%AMMACRO37*
4,1,36,0.0,.019,
-.003299,.018711,
-.006498,.017854,
-.0095,.016454,
-.012213,.014555,
-.014555,.012213,
-.016454,.0095,
-.017854,.006498,
-.018711,.003299,
-.019,0.0,
-.018711,-.003299,
-.017854,-.006498,
-.016454,-.0095,
-.014555,-.012213,
-.012213,-.014555,
-.0095,-.016454,
-.006498,-.017854,
-.003299,-.018711,
0.0,-.019,
.003299,-.018711,
.006498,-.017854,
.0095,-.016454,
.012213,-.014555,
.014555,-.012213,
.016454,-.0095,
.017854,-.006498,
.018711,-.003299,
.019,0.0,
.018711,.003299,
.017854,.006498,
.016454,.0095,
.014555,.012213,
.012213,.014555,
.0095,.016454,
.006498,.017854,
.003299,.018711,
0.0,.019,
0.0*
%
%ADD37MACRO37*%
%AMMACRO26*
4,1,16,.04271,.02503,
.046408,.017233,
.048695,.008913,
.049503,.000322,
.048807,-.008279,
.046628,-.016629,
.043032,-.024473,
.04271,-.02503,
.0478,-.03012,
.052304,-.021362,
.055219,-.011955,
.056456,-.002185,
.055978,.007652,
.053799,.017256,
.049985,.026336,
.0478,.03012,
.04271,.02503,
270.*
4,1,16,.02503,-.04271,
.017233,-.046408,
.008913,-.048695,
.000322,-.049503,
-.008279,-.048807,
-.016629,-.046628,
-.024473,-.043032,
-.02503,-.04271,
-.03012,-.0478,
-.021362,-.052304,
-.011955,-.055219,
-.002185,-.056456,
.007652,-.055978,
.017256,-.053799,
.026336,-.049985,
.03012,-.0478,
.02503,-.04271,
270.*
4,1,16,-.04271,-.02503,
-.046408,-.017233,
-.048695,-.008913,
-.049503,-.000322,
-.048807,.008279,
-.046628,.016629,
-.043032,.024473,
-.04271,.02503,
-.0478,.03012,
-.052304,.021362,
-.055219,.011955,
-.056456,.002185,
-.055978,-.007652,
-.053799,-.017256,
-.049985,-.026336,
-.0478,-.03012,
-.04271,-.02503,
270.*
4,1,16,-.02503,.04271,
-.017233,.046408,
-.008913,.048695,
-.000322,.049503,
.008279,.048807,
.016629,.046628,
.024473,.043032,
.02503,.04271,
.03012,.0478,
.021362,.052304,
.011955,.055219,
.002185,.056456,
-.007652,.055978,
-.017256,.053799,
-.026336,.049985,
-.03012,.0478,
-.02503,.04271,
270.*
%
%ADD26MACRO26*%
%AMMACRO44*
4,1,16,.02657,.01597,
.02894,.011114,
.03043,.005919,
.030995,.000545,
.030619,-.004845,
.029313,-.010088,
.027115,-.015025,
.02657,-.01597,
.03164,-.02104,
.034813,-.015226,
.036928,-.00895,
.037921,-.002401,
.037762,.00422,
.036455,.010713,
.034041,.016881,
.03164,.02104,
.02657,.01597,
90.*
4,1,16,.01597,-.02657,
.011114,-.02894,
.005919,-.03043,
.000545,-.030995,
-.004845,-.030619,
-.010088,-.029313,
-.015025,-.027115,
-.01597,-.02657,
-.02104,-.03164,
-.015226,-.034813,
-.00895,-.036928,
-.002401,-.037921,
.00422,-.037762,
.010713,-.036455,
.016881,-.034041,
.02104,-.03164,
.01597,-.02657,
90.*
4,1,16,-.02657,-.01597,
-.02894,-.011114,
-.03043,-.005919,
-.030995,-.000545,
-.030619,.004845,
-.029313,.010088,
-.027115,.015025,
-.02657,.01597,
-.03164,.02104,
-.034813,.015226,
-.036928,.00895,
-.037921,.002401,
-.037762,-.00422,
-.036455,-.010713,
-.034041,-.016881,
-.03164,-.02104,
-.02657,-.01597,
90.*
4,1,16,-.01597,.02657,
-.011114,.02894,
-.005919,.03043,
-.000545,.030995,
.004845,.030619,
.010088,.029313,
.015025,.027115,
.01597,.02657,
.02104,.03164,
.015226,.034813,
.00895,.036928,
.002401,.037921,
-.00422,.037762,
-.010713,.036455,
-.016881,.034041,
-.02104,.03164,
-.01597,.02657,
90.*
%
%ADD44MACRO44*%
%AMMACRO29*
4,1,16,.02511,.01451,
.027248,.009929,
.028558,.005047,
.029001,.000011,
.028562,-.005025,
.027256,-.009909,
.025121,-.014491,
.02511,-.01451,
.0302,-.01959,
.033143,-.014048,
.035079,-.00808,
.035949,-.001865,
.035727,.004405,
.034419,.010542,
.032065,.016359,
.0302,.01959,
.02511,.01451,
0.0*
4,1,16,.01451,-.02511,
.009929,-.027248,
.005047,-.028558,
.000011,-.029001,
-.005025,-.028562,
-.009909,-.027256,
-.014491,-.025121,
-.01451,-.02511,
-.01959,-.0302,
-.014048,-.033143,
-.00808,-.035079,
-.001865,-.035949,
.004405,-.035727,
.010542,-.034419,
.016359,-.032065,
.01959,-.0302,
.01451,-.02511,
0.0*
4,1,16,-.02511,-.01451,
-.027248,-.009929,
-.028558,-.005047,
-.029001,-.000011,
-.028562,.005025,
-.027256,.009909,
-.025121,.014491,
-.02511,.01451,
-.0302,.01959,
-.033143,.014048,
-.035079,.00808,
-.035949,.001865,
-.035727,-.004405,
-.034419,-.010542,
-.032065,-.016359,
-.0302,-.01959,
-.02511,-.01451,
0.0*
4,1,16,-.01451,.02511,
-.009929,.027248,
-.005047,.028558,
-.000011,.029001,
.005025,.028562,
.009909,.027256,
.014491,.025121,
.01451,.02511,
.01959,.0302,
.014048,.033143,
.00808,.035079,
.001865,.035949,
-.004405,.035727,
-.010542,.034419,
-.016359,.032065,
-.01959,.0302,
-.01451,.02511,
0.0*
%
%ADD29MACRO29*%
%AMMACRO46*
4,1,15,.03682,.01914,
.039584,.012455,
.041146,.005393,
.041457,-.001834,
.040509,-.009005,
.03833,-.015903,
.03682,-.01914,
.04197,-.0243,
.045552,-.016643,
.04775,-.00848,
.048497,-.000059,
.047771,.008363,
.045593,.016531,
.042029,.024197,
.04197,.0243,
.03682,.01914,
90.*
4,1,15,.01914,-.03682,
.012455,-.039584,
.005393,-.041146,
-.001834,-.041457,
-.009005,-.040509,
-.015903,-.03833,
-.01914,-.03682,
-.0243,-.04197,
-.016643,-.045552,
-.00848,-.04775,
-.000059,-.048497,
.008363,-.047771,
.016531,-.045593,
.024197,-.042029,
.0243,-.04197,
.01914,-.03682,
90.*
4,1,15,-.03682,-.01914,
-.039584,-.012455,
-.041146,-.005393,
-.041457,.001834,
-.040509,.009005,
-.03833,.015903,
-.03682,.01914,
-.04197,.0243,
-.045552,.016643,
-.04775,.00848,
-.048497,.000059,
-.047771,-.008363,
-.045593,-.016531,
-.042029,-.024197,
-.04197,-.0243,
-.03682,-.01914,
90.*
4,1,15,-.01914,.03682,
-.012455,.039584,
-.005393,.041146,
.001834,.041457,
.009005,.040509,
.015903,.03833,
.01914,.03682,
.0243,.04197,
.016643,.045552,
.00848,.04775,
.000059,.048497,
-.008363,.047771,
-.016531,.045593,
-.024197,.042029,
-.0243,.04197,
-.01914,.03682,
90.*
%
%ADD46MACRO46*%
%AMMACRO45*
4,1,15,-.03682,.01914,
-.039584,.012455,
-.041146,.005393,
-.041457,-.001834,
-.040509,-.009005,
-.03833,-.015903,
-.03682,-.01914,
-.04197,-.0243,
-.045552,-.016643,
-.04775,-.00848,
-.048497,-.000059,
-.047771,.008363,
-.045593,.016531,
-.042029,.024197,
-.04197,.0243,
-.03682,.01914,
90.*
4,1,15,-.01914,-.03682,
-.012455,-.039584,
-.005393,-.041146,
.001834,-.041457,
.009005,-.040509,
.015903,-.03833,
.01914,-.03682,
.0243,-.04197,
.016643,-.045552,
.00848,-.04775,
.000059,-.048497,
-.008363,-.047771,
-.016531,-.045593,
-.024197,-.042029,
-.0243,-.04197,
-.01914,-.03682,
90.*
4,1,15,.03682,-.01914,
.039584,-.012455,
.041146,-.005393,
.041457,.001834,
.040509,.009005,
.03833,.015903,
.03682,.01914,
.04197,.0243,
.045552,.016643,
.04775,.00848,
.048497,.000059,
.047771,-.008363,
.045593,-.016531,
.042029,-.024197,
.04197,-.0243,
.03682,-.01914,
90.*
4,1,15,.01914,.03682,
.012455,.039584,
.005393,.041146,
-.001834,.041457,
-.009005,.040509,
-.015903,.03833,
-.01914,.03682,
-.0243,.04197,
-.016643,.045552,
-.00848,.04775,
-.000059,.048497,
.008363,.047771,
.016531,.045593,
.024197,.042029,
.0243,.04197,
.01914,.03682,
90.*
%
%ADD45MACRO45*%
%ADD36C,.103*%
%AMMACRO13*
4,1,36,0.0,.005,
.000868,.004924,
.00171,.004698,
.0025,.00433,
.003214,.00383,
.00383,.003214,
.00433,.0025,
.004698,.00171,
.004924,.000868,
.005,0.0,
.004924,-.000868,
.004698,-.00171,
.00433,-.0025,
.00383,-.003214,
.003214,-.00383,
.0025,-.00433,
.00171,-.004698,
.000868,-.004924,
0.0,-.005,
-.000868,-.004924,
-.00171,-.004698,
-.0025,-.00433,
-.003214,-.00383,
-.00383,-.003214,
-.00433,-.0025,
-.004698,-.00171,
-.004924,-.000868,
-.005,0.0,
-.004924,.000868,
-.004698,.00171,
-.00433,.0025,
-.00383,.003214,
-.003214,.00383,
-.0025,.00433,
-.00171,.004698,
-.000868,.004924,
0.0,.005,
270.*
%
%ADD13MACRO13*%
%ADD11C,.125*%
%ADD14C,.117*%
%ADD24C,.155*%
%ADD21C,.237*%
%ADD32C,.256*%
%AMMACRO22*
4,1,36,.0025,0.0,
.002462,.000434,
.002349,.000855,
.002165,.00125,
.001915,.001607,
.001607,.001915,
.00125,.002165,
.000855,.002349,
.000434,.002462,
0.0,.0025,
-.000434,.002462,
-.000855,.002349,
-.00125,.002165,
-.001607,.001915,
-.001915,.001607,
-.002165,.00125,
-.002349,.000855,
-.002462,.000434,
-.0025,0.0,
-.002462,-.000434,
-.002349,-.000855,
-.002165,-.00125,
-.001915,-.001607,
-.001607,-.001915,
-.00125,-.002165,
-.000855,-.002349,
-.000434,-.002462,
0.0,-.0025,
.000434,-.002462,
.000855,-.002349,
.00125,-.002165,
.001607,-.001915,
.001915,-.001607,
.002165,-.00125,
.002349,-.000855,
.002462,-.000434,
.0025,0.0,
90.*
%
%ADD22MACRO22*%
%ADD19C,.186*%
%ADD48C,.187*%
%AMMACRO42*
4,1,36,0.0,.019,
-.003299,.018711,
-.006498,.017854,
-.0095,.016454,
-.012213,.014555,
-.014555,.012213,
-.016454,.0095,
-.017854,.006498,
-.018711,.003299,
-.019,0.0,
-.018711,-.003299,
-.017854,-.006498,
-.016454,-.0095,
-.014555,-.012213,
-.012213,-.014555,
-.0095,-.016454,
-.006498,-.017854,
-.003299,-.018711,
0.0,-.019,
.003299,-.018711,
.006498,-.017854,
.0095,-.016454,
.012213,-.014555,
.014555,-.012213,
.016454,-.0095,
.017854,-.006498,
.018711,-.003299,
.019,0.0,
.018711,.003299,
.017854,.006498,
.016454,.0095,
.014555,.012213,
.012213,.014555,
.0095,.016454,
.006498,.017854,
.003299,.018711,
0.0,.019,
270.*
%
%ADD42MACRO42*%
%AMMACRO10*
4,1,36,.0025,0.0,
.002462,.000434,
.002349,.000855,
.002165,.00125,
.001915,.001607,
.001607,.001915,
.00125,.002165,
.000855,.002349,
.000434,.002462,
0.0,.0025,
-.000434,.002462,
-.000855,.002349,
-.00125,.002165,
-.001607,.001915,
-.001915,.001607,
-.002165,.00125,
-.002349,.000855,
-.002462,.000434,
-.0025,0.0,
-.002462,-.000434,
-.002349,-.000855,
-.002165,-.00125,
-.001915,-.001607,
-.001607,-.001915,
-.00125,-.002165,
-.000855,-.002349,
-.000434,-.002462,
0.0,-.0025,
.000434,-.002462,
.000855,-.002349,
.00125,-.002165,
.001607,-.001915,
.001915,-.001607,
.002165,-.00125,
.002349,-.000855,
.002462,-.000434,
.0025,0.0,
0.0*
%
%ADD10MACRO10*%
%AMMACRO18*
4,1,15,.02217,.01156,
.023841,.007535,
.024787,.00328,
.02498,-.001074,
.024414,-.005395,
.023106,-.009553,
.02217,-.01156,
.0273,-.01669,
.029783,-.011696,
.031362,-.006346,
.031987,-.000804,
.031641,.004763,
.030333,.010185,
.028104,.015297,
.0273,.01669,
.02217,.01156,
270.*
4,1,15,.01156,-.02217,
.007535,-.023841,
.00328,-.024787,
-.001074,-.02498,
-.005395,-.024414,
-.009553,-.023106,
-.01156,-.02217,
-.01669,-.0273,
-.011696,-.029783,
-.006346,-.031362,
-.000804,-.031987,
.004763,-.031641,
.010185,-.030333,
.015297,-.028104,
.01669,-.0273,
.01156,-.02217,
270.*
4,1,15,-.02217,-.01156,
-.023841,-.007535,
-.024787,-.00328,
-.02498,.001074,
-.024414,.005395,
-.023106,.009553,
-.02217,.01156,
-.0273,.01669,
-.029783,.011696,
-.031362,.006346,
-.031987,.000804,
-.031641,-.004763,
-.030333,-.010185,
-.028104,-.015297,
-.0273,-.01669,
-.02217,-.01156,
270.*
4,1,15,-.01156,.02217,
-.007535,.023841,
-.00328,.024787,
.001074,.02498,
.005395,.024414,
.009553,.023106,
.01156,.02217,
.01669,.0273,
.011696,.029783,
.006346,.031362,
.000804,.031987,
-.004763,.031641,
-.010185,.030333,
-.015297,.028104,
-.01669,.0273,
-.01156,.02217,
270.*
%
%ADD18MACRO18*%
%AMMACRO34*
4,1,15,.02438,.01377,
.026401,.009327,
.027619,.004601,
.027999,-.000265,
.027527,-.005123,
.02622,-.009825,
.02438,-.01377,
.02948,-.01887,
.032309,-.013464,
.034156,-.007649,
.034965,-.001602,
.034712,.004494,
.033405,.010454,
.031082,.016095,
.02948,.01887,
.02438,.01377,
270.*
4,1,15,.01377,-.02438,
.009327,-.026401,
.004601,-.027619,
-.000265,-.027999,
-.005123,-.027527,
-.009825,-.02622,
-.01377,-.02438,
-.01887,-.02948,
-.013464,-.032309,
-.007649,-.034156,
-.001602,-.034965,
.004494,-.034712,
.010454,-.033405,
.016095,-.031082,
.01887,-.02948,
.01377,-.02438,
270.*
4,1,15,-.02438,-.01377,
-.026401,-.009327,
-.027619,-.004601,
-.027999,.000265,
-.027527,.005123,
-.02622,.009825,
-.02438,.01377,
-.02948,.01887,
-.032309,.013464,
-.034156,.007649,
-.034965,.001602,
-.034712,-.004494,
-.033405,-.010454,
-.031082,-.016095,
-.02948,-.01887,
-.02438,-.01377,
270.*
4,1,15,-.01377,.02438,
-.009327,.026401,
-.004601,.027619,
.000265,.027999,
.005123,.027527,
.009825,.02622,
.01377,.02438,
.01887,.02948,
.013464,.032309,
.007649,.034156,
.001602,.034965,
-.004494,.034712,
-.010454,.033405,
-.016095,.031082,
-.01887,.02948,
-.01377,.02438,
270.*
%
%ADD34MACRO34*%
%AMMACRO15*
4,1,15,.02475,.01414,
.026829,.009627,
.028094,.004822,
.028504,-.000129,
.028049,-.005077,
.026741,-.009871,
.02475,-.01414,
.02984,-.01923,
.032726,-.013756,
.034617,-.007864,
.035457,-.001734,
.03522,.00445,
.033912,.010498,
.031574,.016227,
.02984,.01923,
.02475,.01414,
270.*
4,1,15,.01414,-.02475,
.009627,-.026829,
.004822,-.028094,
-.000129,-.028504,
-.005077,-.028049,
-.009871,-.026741,
-.01414,-.02475,
-.01923,-.02984,
-.013756,-.032726,
-.007864,-.034617,
-.001734,-.035457,
.00445,-.03522,
.010498,-.033912,
.016227,-.031574,
.01923,-.02984,
.01414,-.02475,
270.*
4,1,15,-.02475,-.01414,
-.026829,-.009627,
-.028094,-.004822,
-.028504,.000129,
-.028049,.005077,
-.026741,.009871,
-.02475,.01414,
-.02984,.01923,
-.032726,.013756,
-.034617,.007864,
-.035457,.001734,
-.03522,-.00445,
-.033912,-.010498,
-.031574,-.016227,
-.02984,-.01923,
-.02475,-.01414,
270.*
4,1,15,-.01414,.02475,
-.009627,.026829,
-.004822,.028094,
.000129,.028504,
.005077,.028049,
.009871,.026741,
.01414,.02475,
.01923,.02984,
.013756,.032726,
.007864,.034617,
.001734,.035457,
-.00445,.03522,
-.010498,.033912,
-.016227,.031574,
-.01923,.02984,
-.01414,.02475,
270.*
%
%ADD15MACRO15*%
%AMMACRO47*
4,1,18,.10783,.07955,
.120006,.059617,
.128535,.037873,
.133159,.014977,
.133736,-.008373,
.130251,-.031469,
.122807,-.053609,
.111633,-.074119,
.10783,-.07955,
.11284,-.08455,
.125808,-.063671,
.134953,-.040857,
.139997,-.016802,
.140788,.007763,
.137301,.032093,
.129642,.055447,
.118045,.077117,
.11284,.08455,
.10783,.07955,
270.*
4,1,18,.07955,-.10783,
.059617,-.120006,
.037873,-.128535,
.014977,-.133159,
-.008373,-.133736,
-.031469,-.130251,
-.053609,-.122807,
-.074119,-.111633,
-.07955,-.10783,
-.08455,-.11284,
-.063671,-.125808,
-.040857,-.134953,
-.016802,-.139997,
.007763,-.140788,
.032093,-.137301,
.055447,-.129642,
.077117,-.118045,
.08455,-.11284,
.07955,-.10783,
270.*
4,1,18,-.10783,-.07955,
-.120006,-.059617,
-.128535,-.037873,
-.133159,-.014977,
-.133736,.008373,
-.130251,.031469,
-.122807,.053609,
-.111633,.074119,
-.10783,.07955,
-.11284,.08455,
-.125808,.063671,
-.134953,.040857,
-.139997,.016802,
-.140788,-.007763,
-.137301,-.032093,
-.129642,-.055447,
-.118045,-.077117,
-.11284,-.08455,
-.10783,-.07955,
270.*
4,1,18,-.07955,.10783,
-.059617,.120006,
-.037873,.128535,
-.014977,.133159,
.008373,.133736,
.031469,.130251,
.053609,.122807,
.074119,.111633,
.07955,.10783,
.08455,.11284,
.063671,.125808,
.040857,.134953,
.016802,.139997,
-.007763,.140788,
-.032093,.137301,
-.055447,.129642,
-.077117,.118045,
-.08455,.11284,
-.07955,.10783,
270.*
%
%ADD47MACRO47*%
%AMMACRO39*
4,1,15,.03682,.01914,
.039584,.012455,
.041146,.005393,
.041457,-.001834,
.040509,-.009005,
.03833,-.015903,
.03682,-.01914,
.04197,-.0243,
.045552,-.016643,
.04775,-.00848,
.048497,-.000059,
.047771,.008363,
.045593,.016531,
.042029,.024197,
.04197,.0243,
.03682,.01914,
270.*
4,1,15,.01914,-.03682,
.012455,-.039584,
.005393,-.041146,
-.001834,-.041457,
-.009005,-.040509,
-.015903,-.03833,
-.01914,-.03682,
-.0243,-.04197,
-.016643,-.045552,
-.00848,-.04775,
-.000059,-.048497,
.008363,-.047771,
.016531,-.045593,
.024197,-.042029,
.0243,-.04197,
.01914,-.03682,
270.*
4,1,15,-.03682,-.01914,
-.039584,-.012455,
-.041146,-.005393,
-.041457,.001834,
-.040509,.009005,
-.03833,.015903,
-.03682,.01914,
-.04197,.0243,
-.045552,.016643,
-.04775,.00848,
-.048497,.000059,
-.047771,-.008363,
-.045593,-.016531,
-.042029,-.024197,
-.04197,-.0243,
-.03682,-.01914,
270.*
4,1,15,-.01914,.03682,
-.012455,.039584,
-.005393,.041146,
.001834,.041457,
.009005,.040509,
.015903,.03833,
.01914,.03682,
.0243,.04197,
.016643,.045552,
.00848,.04775,
.000059,.048497,
-.008363,.047771,
-.016531,.045593,
-.024197,.042029,
-.0243,.04197,
-.01914,.03682,
270.*
%
%ADD39MACRO39*%
%AMMACRO31*
4,1,17,.03273,.02212,
.036074,.0161,
.038322,.009592,
.039405,.002791,
.039291,-.004094,
.037983,-.010854,
.035521,-.017285,
.03273,-.02212,
.03775,-.02715,
.041891,-.020182,
.044759,-.012601,
.046267,-.004638,
.04637,.003467,
.045063,.011466,
.042388,.019117,
.038424,.026188,
.03775,.02715,
.03273,.02212,
270.*
4,1,17,.02212,-.03273,
.0161,-.036074,
.009592,-.038322,
.002791,-.039405,
-.004094,-.039291,
-.010854,-.037983,
-.017285,-.035521,
-.02212,-.03273,
-.02715,-.03775,
-.020182,-.041891,
-.012601,-.044759,
-.004638,-.046267,
.003467,-.04637,
.011466,-.045063,
.019117,-.042388,
.026188,-.038424,
.02715,-.03775,
.02212,-.03273,
270.*
4,1,17,-.03273,-.02212,
-.036074,-.0161,
-.038322,-.009592,
-.039405,-.002791,
-.039291,.004094,
-.037983,.010854,
-.035521,.017285,
-.03273,.02212,
-.03775,.02715,
-.041891,.020182,
-.044759,.012601,
-.046267,.004638,
-.04637,-.003467,
-.045063,-.011466,
-.042388,-.019117,
-.038424,-.026188,
-.03775,-.02715,
-.03273,-.02212,
270.*
4,1,17,-.02212,.03273,
-.0161,.036074,
-.009592,.038322,
-.002791,.039405,
.004094,.039291,
.010854,.037983,
.017285,.035521,
.02212,.03273,
.02715,.03775,
.020182,.041891,
.012601,.044759,
.004638,.046267,
-.003467,.04637,
-.011466,.045063,
-.019117,.042388,
-.026188,.038424,
-.02715,.03775,
-.02212,.03273,
270.*
%
%ADD31MACRO31*%
%AMMACRO41*
4,1,15,-.03682,.01914,
-.039584,.012455,
-.041146,.005393,
-.041457,-.001834,
-.040509,-.009005,
-.03833,-.015903,
-.03682,-.01914,
-.04197,-.0243,
-.045552,-.016643,
-.04775,-.00848,
-.048497,-.000059,
-.047771,.008363,
-.045593,.016531,
-.042029,.024197,
-.04197,.0243,
-.03682,.01914,
270.*
4,1,15,-.01914,-.03682,
-.012455,-.039584,
-.005393,-.041146,
.001834,-.041457,
.009005,-.040509,
.015903,-.03833,
.01914,-.03682,
.0243,-.04197,
.016643,-.045552,
.00848,-.04775,
.000059,-.048497,
-.008363,-.047771,
-.016531,-.045593,
-.024197,-.042029,
-.0243,-.04197,
-.01914,-.03682,
270.*
4,1,15,.03682,-.01914,
.039584,-.012455,
.041146,-.005393,
.041457,.001834,
.040509,.009005,
.03833,.015903,
.03682,.01914,
.04197,.0243,
.045552,.016643,
.04775,.00848,
.048497,.000059,
.047771,-.008363,
.045593,-.016531,
.042029,-.024197,
.04197,-.0243,
.03682,-.01914,
270.*
4,1,15,.01914,.03682,
.012455,.039584,
.005393,.041146,
-.001834,.041457,
-.009005,.040509,
-.015903,.03833,
-.01914,.03682,
-.0243,.04197,
-.016643,.045552,
-.00848,.04775,
-.000059,.048497,
.008363,.047771,
.016531,.045593,
.024197,.042029,
.0243,.04197,
.01914,.03682,
270.*
%
%ADD41MACRO41*%
%ADD49C,.02*%
%ADD50C,.006*%
%ADD56C,.07006*%
%ADD59C,.11022*%
%ADD57C,.11006*%
%ADD55C,.11206*%
%ADD58C,.14306*%
%ADD52C,.12707*%
%ADD53C,.16506*%
%ADD54C,.19606*%
%ADD51C,.28606*%
%ADD60C,.32598*%
G75*
%LPD*%
G75*
G36*
G01X-297025Y-1013390D02*
X3691357D01*
Y1828909D01*
X-297025D01*
Y-1013390D01*
G37*
%LPC*%
G75*
G36*
G01X1048555Y576740D02*
X1049868D01*
Y576736D01*
X1271654D01*
G02X1289335Y559055I0J-17681D01*
G01Y19685D01*
G02X1271654Y2004I-17681J0D01*
G01X19685D01*
G02X2004Y19685I0J17681D01*
G01Y63268D01*
G02X11811Y73075I9807J0D01*
G01X37796D01*
G03X41768Y77047I0J3973D01*
G01Y122323D01*
G03X37796Y126295I-3973J-1D01*
G01X11811D01*
G02X2004Y136102I0J9807D01*
G01Y445787D01*
G02X11811Y455594I9807J0D01*
G01X37795D01*
G03X41768Y459567I0J3973D01*
G01Y504843D01*
G03X37796Y508815I-3973J-1D01*
G01X11811D01*
G02X2004Y518622I0J9807D01*
G01Y559055D01*
G02X19685Y576736I17681J0D01*
G01X1048555D01*
Y576740D01*
G37*
G36*
G01X1283465Y654614D02*
G02X1289339Y648740I0J-5874D01*
G01Y594488D01*
G02X1283465Y588614I-5874J0D01*
G01X607874D01*
G02X602000Y594488I0J5874D01*
G01Y648740D01*
G02X607874Y654614I5874J0D01*
G01X1283465D01*
G37*
%LPD*%
G75*
G36*
G01X1174341Y186396D02*
G02X1175755Y186982I1414J-1413D01*
G01X1190755D01*
G02X1192169Y186396I0J-1999D01*
G01X1193769Y184796D01*
G02X1194355Y183382I-1413J-1414D01*
G01Y150882D01*
G02X1193769Y149468I-1999J0D01*
G01X1192369Y148068D01*
G02X1190955Y147482I-1414J1413D01*
G01X1175239D01*
G02X1173825Y148068I0J1999D01*
G01X1172841Y149052D01*
G02X1172255Y150466I1413J1414D01*
G01Y183482D01*
G02X1172841Y184896I1999J0D01*
G01X1174341Y186396D01*
G37*
G36*
G01X637793Y40521D02*
G02X634698Y44000I408J3479D01*
G02X634903Y45182I3502J1D01*
G03Y45318I-188J68D01*
G02X634698Y46500I3297J1181D01*
G02X638058Y50000I3503J0D01*
G03X638215Y50086I-7J200D01*
G02X641100Y51602I2885J-1987D01*
G02X644602Y48100I0J-3502D01*
G02X643351Y45417I-3503J0D01*
G01X643318Y45389D01*
X643281Y45313D01*
X643268Y44930D01*
X643299Y44852D01*
X643330Y44822D01*
G02X644402Y42300I-2431J-2522D01*
G02X640900Y38798I-3502J0D01*
G02X637939Y40429I0J3503D01*
G03X637793Y40521I-169J-107D01*
G37*
G36*
G01X1075308Y93848D02*
G02X1077200Y94402I1890J-2948D01*
G02Y87398I0J-3502D01*
G02X1075308Y87952I-2J3502D01*
G03X1075092I-108J-168D01*
G02X1073200Y87398I-1890J2948D01*
G02Y94402I0J3502D01*
G02X1075092Y93848I2J-3502D01*
G03X1075308I108J168D01*
G37*
G36*
G01X68400Y93092D02*
X67972Y93157D01*
X67879Y93125D01*
X67844Y93087D01*
G02Y106361I-7214J6637D01*
G01X67879Y106323D01*
X67972Y106291D01*
X68400Y106356D01*
X68479Y106415D01*
X68500Y106461D01*
G02X82795Y115526I14295J-6739D01*
G02Y83922I0J-15802D01*
G02X68500Y92987I0J15804D01*
G01X68479Y93033D01*
X68400Y93092D01*
G37*
G36*
G01X1128569Y123243D02*
X1128931D01*
X1129003Y123273D01*
X1129032Y123301D01*
G02X1131500Y124318I2468J-2486D01*
G02X1132919Y124018I1J-3502D01*
G03X1133081I81J183D01*
G02X1134500Y124318I1418J-3202D01*
G02Y117314I0J-3502D01*
G02X1133081Y117614I-1J3502D01*
G03X1132919I-81J-183D01*
G02X1131500Y117314I-1418J3202D01*
G02X1129032Y118331I0J3503D01*
G01X1129003Y118359D01*
X1128931Y118389D01*
X1128569D01*
X1128497Y118359D01*
X1128468Y118331D01*
G02X1126000Y117314I-2468J2486D01*
G02X1124581Y117614I-1J3502D01*
G03X1124419I-81J-183D01*
G02X1123000Y117314I-1418J3202D01*
G02Y124318I0J3502D01*
G02X1124419Y124018I1J-3502D01*
G03X1124581I81J183D01*
G02X1126000Y124318I1418J-3202D01*
G02X1128468Y123301I0J-3503D01*
G01X1128497Y123273D01*
X1128569Y123243D01*
G37*
G36*
G01X1114049Y129633D02*
G02X1115801Y130102I1751J-3033D01*
G02Y123098I0J-3502D01*
G02X1114049Y123567I-1J3502D01*
G02Y129633I1751J3033D01*
G37*
G36*
G01X709714Y144186D02*
Y144630D01*
X709665Y144718D01*
X709621Y144746D01*
G02X707048Y149408I2937J4662D01*
G02X712559Y154918I5511J-1D01*
G02X717221Y152346I0J-5511D01*
G01X717249Y152302D01*
X717337Y152253D01*
X717781D01*
X717869Y152302D01*
X717897Y152346D01*
G02X722559Y154918I4662J-2939D01*
G02X728070Y149408I1J-5510D01*
G02X725497Y144746I-5510J0D01*
G01X725453Y144718D01*
X725404Y144630D01*
Y144186D01*
X725453Y144098D01*
X725497Y144070D01*
G02Y134746I-2937J-4662D01*
G01X725453Y134718D01*
X725404Y134630D01*
Y134186D01*
X725453Y134098D01*
X725497Y134070D01*
G02Y124746I-2937J-4662D01*
G01X725453Y124718D01*
X725404Y124630D01*
Y124186D01*
X725453Y124098D01*
X725497Y124070D01*
G02X728070Y119408I-2937J-4662D01*
G02X722559Y113898I-5511J1D01*
G02X717897Y116470I0J5511D01*
G01X717869Y116514D01*
X717781Y116563D01*
X717337D01*
X717249Y116514D01*
X717221Y116470D01*
G02X712559Y113898I-4662J2939D01*
G02X707048Y119408I-1J5510D01*
G02X709621Y124070I5510J0D01*
G01X709665Y124098D01*
X709714Y124186D01*
Y124630D01*
X709665Y124718D01*
X709621Y124746D01*
G02Y134070I2937J4662D01*
G01X709665Y134098D01*
X709714Y134186D01*
Y134630D01*
X709665Y134718D01*
X709621Y134746D01*
G02Y144070I2937J4662D01*
G01X709665Y144098D01*
X709714Y144186D01*
G37*
G36*
G01X744714D02*
Y144630D01*
X744665Y144718D01*
X744621Y144746D01*
G02X742048Y149408I2937J4662D01*
G02X747559Y154918I5511J-1D01*
G02X752221Y152346I0J-5511D01*
G01X752249Y152302D01*
X752337Y152253D01*
X752781D01*
X752869Y152302D01*
X752897Y152346D01*
G02X757559Y154918I4662J-2939D01*
G02X763070Y149408I1J-5510D01*
G02X760497Y144746I-5510J0D01*
G01X760453Y144718D01*
X760404Y144630D01*
Y144186D01*
X760453Y144098D01*
X760497Y144070D01*
G02Y134746I-2937J-4662D01*
G01X760453Y134718D01*
X760404Y134630D01*
Y134186D01*
X760453Y134098D01*
X760497Y134070D01*
G02Y124746I-2937J-4662D01*
G01X760453Y124718D01*
X760404Y124630D01*
Y124186D01*
X760453Y124098D01*
X760497Y124070D01*
G02X763070Y119408I-2937J-4662D01*
G02X757559Y113898I-5511J1D01*
G02X752897Y116470I0J5511D01*
G01X752869Y116514D01*
X752781Y116563D01*
X752337D01*
X752249Y116514D01*
X752221Y116470D01*
G02X747559Y113898I-4662J2939D01*
G02X742048Y119408I-1J5510D01*
G02X744621Y124070I5510J0D01*
G01X744665Y124098D01*
X744714Y124186D01*
Y124630D01*
X744665Y124718D01*
X744621Y124746D01*
G02Y134070I2937J4662D01*
G01X744665Y134098D01*
X744714Y134186D01*
Y134630D01*
X744665Y134718D01*
X744621Y134746D01*
G02Y144070I2937J4662D01*
G01X744665Y144098D01*
X744714Y144186D01*
G37*
G36*
G01X779714D02*
Y144630D01*
X779665Y144718D01*
X779621Y144746D01*
G02X777048Y149408I2937J4662D01*
G02X782559Y154918I5511J-1D01*
G02X787221Y152346I0J-5511D01*
G01X787249Y152302D01*
X787337Y152253D01*
X787781D01*
X787869Y152302D01*
X787897Y152346D01*
G02X792559Y154918I4662J-2939D01*
G02X798070Y149408I1J-5510D01*
G02X795497Y144746I-5510J0D01*
G01X795453Y144718D01*
X795404Y144630D01*
Y144186D01*
X795453Y144098D01*
X795497Y144070D01*
G02Y134746I-2937J-4662D01*
G01X795453Y134718D01*
X795404Y134630D01*
Y134186D01*
X795453Y134098D01*
X795497Y134070D01*
G02Y124746I-2937J-4662D01*
G01X795453Y124718D01*
X795404Y124630D01*
Y124186D01*
X795453Y124098D01*
X795497Y124070D01*
G02X798070Y119408I-2937J-4662D01*
G02X792559Y113898I-5511J1D01*
G02X787897Y116470I0J5511D01*
G01X787869Y116514D01*
X787781Y116563D01*
X787337D01*
X787249Y116514D01*
X787221Y116470D01*
G02X782559Y113898I-4662J2939D01*
G02X777048Y119408I-1J5510D01*
G02X779621Y124070I5510J0D01*
G01X779665Y124098D01*
X779714Y124186D01*
Y124630D01*
X779665Y124718D01*
X779621Y124746D01*
G02Y134070I2937J4662D01*
G01X779665Y134098D01*
X779714Y134186D01*
Y134630D01*
X779665Y134718D01*
X779621Y134746D01*
G02Y144070I2937J4662D01*
G01X779665Y144098D01*
X779714Y144186D01*
G37*
G36*
G01X1138250Y164134D02*
G02X1140000Y164602I1749J-3034D01*
G02Y157598I0J-3502D01*
G02X1138250Y158066I-1J3502D01*
G03X1138050I-100J-173D01*
G02X1136300Y157598I-1749J3034D01*
G02Y164602I0J3502D01*
G02X1138050Y164134I1J-3502D01*
G03X1138250I100J173D01*
G37*
G36*
G01X398907Y154463D02*
Y154907D01*
X398858Y154995D01*
X398814Y155023D01*
G02X396242Y159685I2939J4662D01*
G02X401752Y165196I5510J1D01*
G02X406414Y162623I0J-5510D01*
G01X406442Y162579D01*
X406530Y162530D01*
X406974D01*
X407062Y162579D01*
X407090Y162623D01*
G02X411752Y165196I4662J-2937D01*
G02X417262Y159685I-1J-5511D01*
G02X414690Y155023I-5511J0D01*
G01X414646Y154995D01*
X414597Y154907D01*
Y154463D01*
X414646Y154375D01*
X414690Y154347D01*
G02Y145023I-2939J-4662D01*
G01X414646Y144995D01*
X414597Y144907D01*
Y144463D01*
X414646Y144375D01*
X414690Y144347D01*
G02Y135023I-2939J-4662D01*
G01X414646Y134995D01*
X414597Y134907D01*
Y134463D01*
X414646Y134375D01*
X414690Y134347D01*
G02X417262Y129685I-2939J-4662D01*
G02X411752Y124174I-5510J-1D01*
G02X407090Y126747I0J5510D01*
G01X407062Y126791D01*
X406974Y126840D01*
X406530D01*
X406442Y126791D01*
X406414Y126747D01*
G02X401752Y124174I-4662J2937D01*
G02X396242Y129685I1J5511D01*
G02X398814Y134347I5511J0D01*
G01X398858Y134375D01*
X398907Y134463D01*
Y134907D01*
X398858Y134995D01*
X398814Y135023D01*
G02Y144347I2939J4662D01*
G01X398858Y144375D01*
X398907Y144463D01*
Y144907D01*
X398858Y144995D01*
X398814Y145023D01*
G02Y154347I2939J4662D01*
G01X398858Y154375D01*
X398907Y154463D01*
G37*
G36*
G01X433907D02*
Y154907D01*
X433858Y154995D01*
X433814Y155023D01*
G02X431242Y159685I2939J4662D01*
G02X436752Y165196I5510J1D01*
G02X441414Y162623I0J-5510D01*
G01X441442Y162579D01*
X441530Y162530D01*
X441974D01*
X442062Y162579D01*
X442090Y162623D01*
G02X446752Y165196I4662J-2937D01*
G02X452262Y159685I-1J-5511D01*
G02X449690Y155023I-5511J0D01*
G01X449646Y154995D01*
X449597Y154907D01*
Y154463D01*
X449646Y154375D01*
X449690Y154347D01*
G02Y145023I-2939J-4662D01*
G01X449646Y144995D01*
X449597Y144907D01*
Y144463D01*
X449646Y144375D01*
X449690Y144347D01*
G02Y135023I-2939J-4662D01*
G01X449646Y134995D01*
X449597Y134907D01*
Y134463D01*
X449646Y134375D01*
X449690Y134347D01*
G02X452262Y129685I-2939J-4662D01*
G02X446752Y124174I-5510J-1D01*
G02X442090Y126747I0J5510D01*
G01X442062Y126791D01*
X441974Y126840D01*
X441530D01*
X441442Y126791D01*
X441414Y126747D01*
G02X436752Y124174I-4662J2937D01*
G02X431242Y129685I1J5511D01*
G02X433814Y134347I5511J0D01*
G01X433858Y134375D01*
X433907Y134463D01*
Y134907D01*
X433858Y134995D01*
X433814Y135023D01*
G02Y144347I2939J4662D01*
G01X433858Y144375D01*
X433907Y144463D01*
Y144907D01*
X433858Y144995D01*
X433814Y145023D01*
G02Y154347I2939J4662D01*
G01X433858Y154375D01*
X433907Y154463D01*
G37*
G36*
G01X468907D02*
Y154907D01*
X468858Y154995D01*
X468814Y155023D01*
G02X466242Y159685I2939J4662D01*
G02X471752Y165196I5510J1D01*
G02X476414Y162623I0J-5510D01*
G01X476442Y162579D01*
X476530Y162530D01*
X476974D01*
X477062Y162579D01*
X477090Y162623D01*
G02X481752Y165196I4662J-2937D01*
G02X487262Y159685I-1J-5511D01*
G02X484690Y155023I-5511J0D01*
G01X484646Y154995D01*
X484597Y154907D01*
Y154463D01*
X484646Y154375D01*
X484690Y154347D01*
G02Y145023I-2939J-4662D01*
G01X484646Y144995D01*
X484597Y144907D01*
Y144463D01*
X484646Y144375D01*
X484690Y144347D01*
G02Y135023I-2939J-4662D01*
G01X484646Y134995D01*
X484597Y134907D01*
Y134463D01*
X484646Y134375D01*
X484690Y134347D01*
G02X487262Y129685I-2939J-4662D01*
G02X481752Y124174I-5510J-1D01*
G02X477090Y126747I0J5510D01*
G01X477062Y126791D01*
X476974Y126840D01*
X476530D01*
X476442Y126791D01*
X476414Y126747D01*
G02X471752Y124174I-4662J2937D01*
G02X466242Y129685I1J5511D01*
G02X468814Y134347I5511J0D01*
G01X468858Y134375D01*
X468907Y134463D01*
Y134907D01*
X468858Y134995D01*
X468814Y135023D01*
G02Y144347I2939J4662D01*
G01X468858Y144375D01*
X468907Y144463D01*
Y144907D01*
X468858Y144995D01*
X468814Y145023D01*
G02Y154347I2939J4662D01*
G01X468858Y154375D01*
X468907Y154463D01*
G37*
G36*
G01X1018570Y169974D02*
X1018623Y170080D01*
G03X1018636Y170225I-179J89D01*
G02X1018498Y171200I3364J973D01*
G02X1025502I3502J0D01*
G02X1023239Y167924I-3503J0D01*
G03X1023130Y167826I70J-187D01*
G01X1023077Y167720D01*
G03X1023064Y167575I179J-89D01*
G02X1023202Y166600I-3364J-973D01*
G02X1023053Y165589I-3502J0D01*
G01X1023042Y165551D01*
X1023049Y165475D01*
X1023211Y165158D01*
X1023269Y165108D01*
X1023306Y165095D01*
G02X1025670Y161783I-1138J-3312D01*
G02X1024458Y159133I-3503J0D01*
G01X1024424Y159104D01*
X1024389Y159026D01*
Y158634D01*
X1024424Y158556D01*
X1024458Y158527D01*
G02X1025670Y155877I-2291J-2650D01*
G02X1022168Y152374I-3502J-1D01*
G02X1021810Y152393I6J3503D01*
G01X1021764Y152398D01*
X1021678Y152366D01*
X1021395Y152070D01*
X1021367Y151983D01*
X1021374Y151936D01*
G02X1021412Y151424I-3465J-515D01*
G02X1014406I-3503J0D01*
G02X1014645Y152693I3503J-3D01*
G03X1014641Y152848I-187J73D01*
G02X1014334Y154280I3196J1434D01*
G02X1015483Y156874I3503J0D01*
G03X1015548Y157037I-134J148D01*
G02X1015538Y157310I3492J265D01*
G02X1015837Y158728I3502J2D01*
G03Y158891I-183J82D01*
G02X1015528Y160330I3193J1438D01*
G02X1017278Y163363I3503J0D01*
G01X1017320Y163387D01*
X1017372Y163467D01*
X1017417Y163885D01*
X1017383Y163973D01*
X1017347Y164006D01*
G02X1016198Y166600I2354J2594D01*
G02X1018461Y169876I3503J0D01*
G03X1018570Y169974I-70J187D01*
G37*
G36*
G01X1138250Y175334D02*
G02X1140000Y175802I1749J-3034D01*
G02Y168798I0J-3502D01*
G02X1138250Y169266I-1J3502D01*
G03X1138050I-100J-173D01*
G02X1136300Y168798I-1749J3034D01*
G02Y175802I0J3502D01*
G02X1138050Y175334I1J-3502D01*
G03X1138250I100J173D01*
G37*
G36*
G01X1141998Y186729D02*
G02X1143490Y187062I1491J-3169D01*
G02Y180058I0J-3502D01*
G02X1141998Y180391I-1J3502D01*
G03X1141828I-85J-181D01*
G02X1140336Y180058I-1491J3169D01*
G02Y187062I0J3502D01*
G02X1141828Y186729I1J-3502D01*
G03X1141998I85J181D01*
G37*
G36*
G01X1019816Y188686D02*
G02X1020116Y187267I-3202J-1418D01*
G02X1013112I-3502J0D01*
G02X1013412Y188686I3502J1D01*
G03Y188848I-183J81D01*
G02X1013112Y190267I3202J1418D01*
G02X1020116I3502J0D01*
G02X1019816Y188848I-3502J-1D01*
G03Y188686I183J-81D01*
G37*
G36*
G01X1090702Y199419D02*
G02X1091002Y198000I-3202J-1418D01*
G02X1083998I-3502J0D01*
G02X1084298Y199419I3502J1D01*
G03Y199581I-183J81D01*
G02X1083998Y201000I3202J1418D01*
G02X1091002I3502J0D01*
G02X1090702Y199581I-3502J-1D01*
G03Y199419I183J-81D01*
G37*
G36*
G01X587867Y200690D02*
G02X586998Y203000I2633J2309D01*
G02X587203Y204182I3502J1D01*
G03Y204318I-188J68D01*
G02X586998Y205500I3297J1181D01*
G02X594002I3502J0D01*
G02X593797Y204318I-3502J-1D01*
G03Y204182I188J-68D01*
G02X594002Y203000I-3297J-1181D01*
G02X593133Y200690I-3502J-1D01*
G03X593083Y200559I150J-132D01*
G01Y200441D01*
G03X593133Y200310I200J1D01*
G02X594002Y198000I-2633J-2309D01*
G02X593797Y196818I-3502J-1D01*
G03Y196682I188J-68D01*
G02X594002Y195500I-3297J-1181D01*
G02X586998I-3502J0D01*
G02X587203Y196682I3502J1D01*
G03Y196818I-188J68D01*
G02X586998Y198000I3297J1181D01*
G02X587867Y200310I3502J1D01*
G03X587917Y200441I-150J132D01*
G01Y200559D01*
G03X587867Y200690I-200J-1D01*
G37*
G36*
G01X609367D02*
G02X608498Y203000I2633J2309D01*
G02X608703Y204182I3502J1D01*
G03Y204318I-188J68D01*
G02X608498Y205500I3297J1181D01*
G02X615502I3502J0D01*
G02X615297Y204318I-3502J-1D01*
G03Y204182I188J-68D01*
G02X615502Y203000I-3297J-1181D01*
G02X614633Y200690I-3502J-1D01*
G03X614583Y200559I150J-132D01*
G01Y200441D01*
G03X614633Y200310I200J1D01*
G02X615502Y198000I-2633J-2309D01*
G02X615297Y196818I-3502J-1D01*
G03Y196682I188J-68D01*
G02X615502Y195500I-3297J-1181D01*
G02X608498I-3502J0D01*
G02X608703Y196682I3502J1D01*
G03Y196818I-188J68D01*
G02X608498Y198000I3297J1181D01*
G02X609367Y200310I3502J1D01*
G03X609417Y200441I-150J132D01*
G01Y200559D01*
G03X609367Y200690I-200J-1D01*
G37*
G36*
G01X630867D02*
G02X629998Y203000I2633J2309D01*
G02X630203Y204182I3502J1D01*
G03Y204318I-188J68D01*
G02X629998Y205500I3297J1181D01*
G02X637002I3502J0D01*
G02X636797Y204318I-3502J-1D01*
G03Y204182I188J-68D01*
G02X637002Y203000I-3297J-1181D01*
G02X636133Y200690I-3502J-1D01*
G03X636083Y200559I150J-132D01*
G01Y200441D01*
G03X636133Y200310I200J1D01*
G02X637002Y198000I-2633J-2309D01*
G02X636797Y196818I-3502J-1D01*
G03Y196682I188J-68D01*
G02X637002Y195500I-3297J-1181D01*
G02X629998I-3502J0D01*
G02X630203Y196682I3502J1D01*
G03Y196818I-188J68D01*
G02X629998Y198000I3297J1181D01*
G02X630867Y200310I3502J1D01*
G03X630917Y200441I-150J132D01*
G01Y200559D01*
G03X630867Y200690I-200J-1D01*
G37*
G36*
G01X652367D02*
G02X651498Y203000I2633J2309D01*
G02X651703Y204182I3502J1D01*
G03Y204318I-188J68D01*
G02X651498Y205500I3297J1181D01*
G02X658502I3502J0D01*
G02X658297Y204318I-3502J-1D01*
G03Y204182I188J-68D01*
G02X658502Y203000I-3297J-1181D01*
G02X657633Y200690I-3502J-1D01*
G03X657583Y200559I150J-132D01*
G01Y200441D01*
G03X657633Y200310I200J1D01*
G02X658502Y198000I-2633J-2309D01*
G02X658297Y196818I-3502J-1D01*
G03Y196682I188J-68D01*
G02X658502Y195500I-3297J-1181D01*
G02X651498I-3502J0D01*
G02X651703Y196682I3502J1D01*
G03Y196818I-188J68D01*
G02X651498Y198000I3297J1181D01*
G02X652367Y200310I3502J1D01*
G03X652417Y200441I-150J132D01*
G01Y200559D01*
G03X652367Y200690I-200J-1D01*
G37*
G36*
G01X673867D02*
G02X672998Y203000I2633J2309D01*
G02X673203Y204182I3502J1D01*
G03Y204318I-188J68D01*
G02X672998Y205500I3297J1181D01*
G02X680002I3502J0D01*
G02X679797Y204318I-3502J-1D01*
G03Y204182I188J-68D01*
G02X680002Y203000I-3297J-1181D01*
G02X679133Y200690I-3502J-1D01*
G03X679083Y200559I150J-132D01*
G01Y200441D01*
G03X679133Y200310I200J1D01*
G02X680002Y198000I-2633J-2309D01*
G02X679797Y196818I-3502J-1D01*
G03Y196682I188J-68D01*
G02X680002Y195500I-3297J-1181D01*
G02X672998I-3502J0D01*
G02X673203Y196682I3502J1D01*
G03Y196818I-188J68D01*
G02X672998Y198000I3297J1181D01*
G02X673867Y200310I3502J1D01*
G03X673917Y200441I-150J132D01*
G01Y200559D01*
G03X673867Y200690I-200J-1D01*
G37*
G36*
G01X695357D02*
G02X694488Y203000I2633J2309D01*
G02X694693Y204182I3502J1D01*
G03Y204318I-188J68D01*
G02X694488Y205500I3297J1181D01*
G02X701492I3502J0D01*
G02X701287Y204318I-3502J-1D01*
G03Y204182I188J-68D01*
G02X701492Y203000I-3297J-1181D01*
G02X700623Y200690I-3502J-1D01*
G03X700573Y200559I150J-132D01*
G01Y200441D01*
G03X700623Y200310I200J1D01*
G02X701492Y198000I-2633J-2309D01*
G02X701287Y196818I-3502J-1D01*
G03Y196682I188J-68D01*
G02X701492Y195500I-3297J-1181D01*
G02X694488I-3502J0D01*
G02X694693Y196682I3502J1D01*
G03Y196818I-188J68D01*
G02X694488Y198000I3297J1181D01*
G02X695357Y200310I3502J1D01*
G03X695407Y200441I-150J132D01*
G01Y200559D01*
G03X695357Y200690I-200J-1D01*
G37*
G36*
G01X716857D02*
G02X715988Y203000I2633J2309D01*
G02X716193Y204182I3502J1D01*
G03Y204318I-188J68D01*
G02X715988Y205500I3297J1181D01*
G02X722992I3502J0D01*
G02X722787Y204318I-3502J-1D01*
G03Y204182I188J-68D01*
G02X722992Y203000I-3297J-1181D01*
G02X722123Y200690I-3502J-1D01*
G03X722073Y200559I150J-132D01*
G01Y200441D01*
G03X722123Y200310I200J1D01*
G02X722992Y198000I-2633J-2309D01*
G02X722787Y196818I-3502J-1D01*
G03Y196682I188J-68D01*
G02X722992Y195500I-3297J-1181D01*
G02X715988I-3502J0D01*
G02X716193Y196682I3502J1D01*
G03Y196818I-188J68D01*
G02X715988Y198000I3297J1181D01*
G02X716857Y200310I3502J1D01*
G03X716907Y200441I-150J132D01*
G01Y200559D01*
G03X716857Y200690I-200J-1D01*
G37*
G36*
G01X173348Y199403D02*
G02X171158Y202650I1312J3247D01*
G02X171501Y204164I3503J2D01*
G03Y204336I-180J86D01*
G02X171158Y205850I3160J1512D01*
G02X178162I3502J0D01*
G02X177819Y204336I-3503J-2D01*
G03Y204164I180J-86D01*
G02X178162Y202650I-3160J-1512D01*
G02X177677Y200871I-3502J-1D01*
G01X177655Y200834D01*
X177646Y200747D01*
X177772Y200377D01*
X177832Y200314D01*
X177872Y200297D01*
G02X177932Y200273I-1271J-3264D01*
G03X178088I78J184D01*
G02X179460Y200552I1370J-3223D01*
G02X180784Y200292I0J-3501D01*
G03X180936I76J186D01*
G02X182260Y200552I1324J-3241D01*
G02Y193548I0J-3502D01*
G02X180936Y193808I0J3501D01*
G03X180784I-76J-186D01*
G02X179460Y193548I-1324J3241D01*
G02X178088Y193827I-2J3502D01*
G03X177932I-78J-184D01*
G02X176560Y193548I-1370J3223D01*
G02X173058Y197050I0J3502D01*
G02X173543Y198829I3502J1D01*
G01X173565Y198866D01*
X173574Y198953D01*
X173448Y199323D01*
X173388Y199386D01*
X173348Y199403D01*
G37*
G36*
G01X280367Y201190D02*
G02X279498Y203500I2633J2309D01*
G02X279703Y204682I3502J1D01*
G03Y204818I-188J68D01*
G02X279498Y206000I3297J1181D01*
G02X286502I3502J0D01*
G02X286297Y204818I-3502J-1D01*
G03Y204682I188J-68D01*
G02X286502Y203500I-3297J-1181D01*
G02X285633Y201190I-3502J-1D01*
G03X285583Y201059I150J-132D01*
G01Y200941D01*
G03X285633Y200810I200J1D01*
G02X286502Y198500I-2633J-2309D01*
G02X286297Y197318I-3502J-1D01*
G03Y197182I188J-68D01*
G02X286502Y196000I-3297J-1181D01*
G02X279498I-3502J0D01*
G02X279703Y197182I3502J1D01*
G03Y197318I-188J68D01*
G02X279498Y198500I3297J1181D01*
G02X280367Y200810I3502J1D01*
G03X280417Y200941I-150J132D01*
G01Y201059D01*
G03X280367Y201190I-200J-1D01*
G37*
G36*
G01X301867D02*
G02X300998Y203500I2633J2309D01*
G02X301203Y204682I3502J1D01*
G03Y204818I-188J68D01*
G02X300998Y206000I3297J1181D01*
G02X308002I3502J0D01*
G02X307797Y204818I-3502J-1D01*
G03Y204682I188J-68D01*
G02X308002Y203500I-3297J-1181D01*
G02X307133Y201190I-3502J-1D01*
G03X307083Y201059I150J-132D01*
G01Y200941D01*
G03X307133Y200810I200J1D01*
G02X308002Y198500I-2633J-2309D01*
G02X307797Y197318I-3502J-1D01*
G03Y197182I188J-68D01*
G02X308002Y196000I-3297J-1181D01*
G02X300998I-3502J0D01*
G02X301203Y197182I3502J1D01*
G03Y197318I-188J68D01*
G02X300998Y198500I3297J1181D01*
G02X301867Y200810I3502J1D01*
G03X301917Y200941I-150J132D01*
G01Y201059D01*
G03X301867Y201190I-200J-1D01*
G37*
G36*
G01X323367D02*
G02X322498Y203500I2633J2309D01*
G02X322703Y204682I3502J1D01*
G03Y204818I-188J68D01*
G02X322498Y206000I3297J1181D01*
G02X329502I3502J0D01*
G02X329297Y204818I-3502J-1D01*
G03Y204682I188J-68D01*
G02X329502Y203500I-3297J-1181D01*
G02X328633Y201190I-3502J-1D01*
G03X328583Y201059I150J-132D01*
G01Y200941D01*
G03X328633Y200810I200J1D01*
G02X329502Y198500I-2633J-2309D01*
G02X329297Y197318I-3502J-1D01*
G03Y197182I188J-68D01*
G02X329502Y196000I-3297J-1181D01*
G02X322498I-3502J0D01*
G02X322703Y197182I3502J1D01*
G03Y197318I-188J68D01*
G02X322498Y198500I3297J1181D01*
G02X323367Y200810I3502J1D01*
G03X323417Y200941I-150J132D01*
G01Y201059D01*
G03X323367Y201190I-200J-1D01*
G37*
G36*
G01X344867D02*
G02X343998Y203500I2633J2309D01*
G02X344203Y204682I3502J1D01*
G03Y204818I-188J68D01*
G02X343998Y206000I3297J1181D01*
G02X351002I3502J0D01*
G02X350797Y204818I-3502J-1D01*
G03Y204682I188J-68D01*
G02X351002Y203500I-3297J-1181D01*
G02X350133Y201190I-3502J-1D01*
G03X350083Y201059I150J-132D01*
G01Y200941D01*
G03X350133Y200810I200J1D01*
G02X351002Y198500I-2633J-2309D01*
G02X350797Y197318I-3502J-1D01*
G03Y197182I188J-68D01*
G02X351002Y196000I-3297J-1181D01*
G02X343998I-3502J0D01*
G02X344203Y197182I3502J1D01*
G03Y197318I-188J68D01*
G02X343998Y198500I3297J1181D01*
G02X344867Y200810I3502J1D01*
G03X344917Y200941I-150J132D01*
G01Y201059D01*
G03X344867Y201190I-200J-1D01*
G37*
G36*
G01X366367D02*
G02X365498Y203500I2633J2309D01*
G02X365703Y204682I3502J1D01*
G03Y204818I-188J68D01*
G02X365498Y206000I3297J1181D01*
G02X372502I3502J0D01*
G02X372297Y204818I-3502J-1D01*
G03Y204682I188J-68D01*
G02X372502Y203500I-3297J-1181D01*
G02X371633Y201190I-3502J-1D01*
G03X371583Y201059I150J-132D01*
G01Y200941D01*
G03X371633Y200810I200J1D01*
G02X372502Y198500I-2633J-2309D01*
G02X372297Y197318I-3502J-1D01*
G03Y197182I188J-68D01*
G02X372502Y196000I-3297J-1181D01*
G02X365498I-3502J0D01*
G02X365703Y197182I3502J1D01*
G03Y197318I-188J68D01*
G02X365498Y198500I3297J1181D01*
G02X366367Y200810I3502J1D01*
G03X366417Y200941I-150J132D01*
G01Y201059D01*
G03X366367Y201190I-200J-1D01*
G37*
G36*
G01X387867D02*
G02X386998Y203500I2633J2309D01*
G02X387203Y204682I3502J1D01*
G03Y204818I-188J68D01*
G02X386998Y206000I3297J1181D01*
G02X394002I3502J0D01*
G02X393797Y204818I-3502J-1D01*
G03Y204682I188J-68D01*
G02X394002Y203500I-3297J-1181D01*
G02X393133Y201190I-3502J-1D01*
G03X393083Y201059I150J-132D01*
G01Y200941D01*
G03X393133Y200810I200J1D01*
G02X394002Y198500I-2633J-2309D01*
G02X393797Y197318I-3502J-1D01*
G03Y197182I188J-68D01*
G02X394002Y196000I-3297J-1181D01*
G02X386998I-3502J0D01*
G02X387203Y197182I3502J1D01*
G03Y197318I-188J68D01*
G02X386998Y198500I3297J1181D01*
G02X387867Y200810I3502J1D01*
G03X387917Y200941I-150J132D01*
G01Y201059D01*
G03X387867Y201190I-200J-1D01*
G37*
G36*
G01X409367D02*
G02X408498Y203500I2633J2309D01*
G02X408703Y204682I3502J1D01*
G03Y204818I-188J68D01*
G02X408498Y206000I3297J1181D01*
G02X415502I3502J0D01*
G02X415297Y204818I-3502J-1D01*
G03Y204682I188J-68D01*
G02X415502Y203500I-3297J-1181D01*
G02X414633Y201190I-3502J-1D01*
G03X414583Y201059I150J-132D01*
G01Y200941D01*
G03X414633Y200810I200J1D01*
G02X415502Y198500I-2633J-2309D01*
G02X415297Y197318I-3502J-1D01*
G03Y197182I188J-68D01*
G02X415502Y196000I-3297J-1181D01*
G02X408498I-3502J0D01*
G02X408703Y197182I3502J1D01*
G03Y197318I-188J68D01*
G02X408498Y198500I3297J1181D01*
G02X409367Y200810I3502J1D01*
G03X409417Y200941I-150J132D01*
G01Y201059D01*
G03X409367Y201190I-200J-1D01*
G37*
G36*
G01X190958Y206781D02*
G02X190658Y208200I3202J1418D01*
G02X194160Y211702I3502J0D01*
G02X195579Y211402I1J-3502D01*
G03X195741I81J183D01*
G02X197160Y211702I1418J-3202D01*
G02X198579Y211402I1J-3502D01*
G03X198741I81J183D01*
G02X200160Y211702I1418J-3202D01*
G02X203662Y208200I0J-3502D01*
G02X203362Y206781I-3502J-1D01*
G03Y206619I183J-81D01*
G02X203662Y205200I-3202J-1418D01*
G02X200160Y201698I-3502J0D01*
G02X198741Y201998I-1J3502D01*
G03X198579I-81J-183D01*
G02X197160Y201698I-1418J3202D01*
G02X195741Y201998I-1J3502D01*
G03X195579I-81J-183D01*
G02X194160Y201698I-1418J3202D01*
G02X190658Y205200I0J3502D01*
G02X190958Y206619I3502J1D01*
G03Y206781I-183J81D01*
G37*
G36*
G01X188462Y206769D02*
G02X188762Y205350I-3202J-1418D01*
G02X181758I-3502J0D01*
G02X182058Y206769I3502J1D01*
G03Y206931I-183J81D01*
G02X181758Y208350I3202J1418D01*
G02X188762I3502J0D01*
G02X188462Y206931I-3502J-1D01*
G03Y206769I183J-81D01*
G37*
G36*
G01X149247Y224908D02*
G02X148832Y226563I3087J1654D01*
G02X149247Y228218I3502J1D01*
G03Y228408I-176J95D01*
G02X148832Y230063I3087J1654D01*
G02X152065Y233555I3502J0D01*
G03X152211Y233636I-15J200D01*
G02X155034Y235066I2824J-2073D01*
G02X158536Y231563I-1J-3503D01*
G02X158121Y229908I-3502J-1D01*
G03Y229718I176J-95D01*
G02X158536Y228063I-3087J-1654D01*
G02X158121Y226408I-3502J-1D01*
G03Y226218I176J-95D01*
G02X158536Y224563I-3087J-1654D01*
G02X155303Y221071I-3502J0D01*
G03X155157Y220990I15J-200D01*
G02X154140Y220062I-2823J2073D01*
G03X154048Y219846I103J-171D01*
G02X154136Y219063I-3414J-780D01*
G02X147132I-3502J0D01*
G02X148828Y222064I3503J0D01*
G03X148920Y222280I-103J171D01*
G02X148832Y223063I3414J780D01*
G02X149247Y224718I3502J1D01*
G03Y224908I-176J95D01*
G37*
G36*
G01X1064581Y261202D02*
G02X1066000Y261502I1418J-3202D01*
G02X1067419Y261202I1J-3502D01*
G03X1067581I81J183D01*
G02X1069000Y261502I1418J-3202D01*
G02X1070419Y261202I1J-3502D01*
G03X1070581I81J183D01*
G02X1072000Y261502I1418J-3202D01*
G02X1075502Y258000I0J-3502D01*
G02X1075202Y256581I-3502J-1D01*
G03Y256419I183J-81D01*
G02X1075502Y255000I-3202J-1418D01*
G02X1072000Y251498I-3502J0D01*
G02X1070581Y251798I-1J3502D01*
G03X1070419I-81J-183D01*
G02X1069611Y251551I-1420J3202D01*
G03X1069449Y251389I35J-197D01*
G02X1069202Y250581I-3449J612D01*
G03Y250419I183J-81D01*
G02X1069449Y249611I-3202J-1420D01*
G03X1069611Y249449I197J35D01*
G02X1070419Y249202I-612J-3449D01*
G03X1070581I81J183D01*
G02X1072000Y249502I1418J-3202D01*
G02X1075502Y246000I0J-3502D01*
G02X1075202Y244581I-3502J-1D01*
G03Y244419I183J-81D01*
G02X1075502Y243000I-3202J-1418D01*
G02X1072000Y239498I-3502J0D01*
G02X1070581Y239798I-1J3502D01*
G03X1070419I-81J-183D01*
G02X1069000Y239498I-1418J3202D01*
G02X1067581Y239798I-1J3502D01*
G03X1067419I-81J-183D01*
G02X1066000Y239498I-1418J3202D01*
G02X1064581Y239798I-1J3502D01*
G03X1064419I-81J-183D01*
G02X1063000Y239498I-1418J3202D01*
G02X1061581Y239798I-1J3502D01*
G03X1061419I-81J-183D01*
G02X1060000Y239498I-1418J3202D01*
G02X1056498Y243000I0J3502D01*
G02X1056798Y244419I3502J1D01*
G03Y244581I-183J81D01*
G02X1056498Y246000I3202J1418D01*
G02X1056798Y247419I3502J1D01*
G03Y247581I-183J81D01*
G02X1056498Y249000I3202J1418D01*
G02X1056798Y250419I3502J1D01*
G03Y250581I-183J81D01*
G02X1056498Y252000I3202J1418D01*
G02X1056798Y253419I3502J1D01*
G03Y253581I-183J81D01*
G02X1056498Y255000I3202J1418D01*
G02X1056798Y256419I3502J1D01*
G03Y256581I-183J81D01*
G02X1056498Y258000I3202J1418D01*
G02X1060000Y261502I3502J0D01*
G02X1061419Y261202I1J-3502D01*
G03X1061581I81J183D01*
G02X1063000Y261502I1418J-3202D01*
G02X1064419Y261202I1J-3502D01*
G03X1064581I81J183D01*
G37*
G36*
G01X105398Y257141D02*
G02X105098Y258560I3202J1418D01*
G02X105398Y259979I3502J1D01*
G03Y260141I-183J81D01*
G02X105098Y261560I3202J1418D01*
G02X108600Y265062I3502J0D01*
G02X110019Y264762I1J-3502D01*
G03X110181I81J183D01*
G02X111600Y265062I1418J-3202D01*
G02X115102Y261560I0J-3502D01*
G02X114802Y260141I-3502J-1D01*
G03Y259979I183J-81D01*
G02X115102Y258560I-3202J-1418D01*
G02X114802Y257141I-3502J-1D01*
G03Y256979I183J-81D01*
G02X115102Y255560I-3202J-1418D01*
G02X111600Y252058I-3502J0D01*
G02X110181Y252358I-1J3502D01*
G03X110019I-81J-183D01*
G02X108600Y252058I-1418J3202D01*
G02X105098Y255560I0J3502D01*
G02X105398Y256979I3502J1D01*
G03Y257141I-183J81D01*
G37*
G36*
G01X43554Y281934D02*
X44006D01*
X44098Y281986D01*
X44125Y282032D01*
G02X48780Y284694I4656J-2741D01*
G02X54182Y279291I-1J-5403D01*
G02X53113Y276064I-5402J-1D01*
G03Y275825I160J-119D01*
G02X54182Y272598I-4333J-3226D01*
G02X48780Y267196I-5402J0D01*
G02X44125Y269857I0J5402D01*
G01X44098Y269903D01*
X44006Y269955D01*
X43554D01*
X43462Y269903D01*
X43435Y269857D01*
G02X38780Y267196I-4655J2741D01*
G02X33378Y272598I0J5402D01*
G02X34447Y275825I5402J1D01*
G03Y276064I-160J120D01*
G02X33378Y279291I4333J3226D01*
G02X38780Y284694I5402J1D01*
G02X43435Y282032I-1J-5403D01*
G01X43462Y281986D01*
X43554Y281934D01*
G37*
G36*
G01X561243Y272218D02*
X561401Y272604D01*
X561394Y272697D01*
X561369Y272738D01*
G02X560128Y277204I7411J4465D01*
G02X568780Y285856I8652J0D01*
G02X575949Y282049I1J-8652D01*
G01X575977Y282008D01*
X576064Y281961D01*
X576496D01*
X576583Y282008D01*
X576611Y282049D01*
G02X583780Y285856I7168J-4845D01*
G02Y268552I0J-8652D01*
G02X576611Y272359I-1J8652D01*
G01X576583Y272400D01*
X576496Y272447D01*
X576064D01*
X575977Y272400D01*
X575949Y272359D01*
G02X568780Y268552I-7168J4845D01*
G02X567856Y268601I-4J8652D01*
G01X567808Y268606D01*
X567721Y268574D01*
X567437Y268268D01*
X567411Y268178D01*
X567420Y268131D01*
G02X567504Y267204I-5018J-922D01*
G02X557300I-5102J0D01*
G02X561126Y272144I5102J0D01*
G01X561173Y272157D01*
X561243Y272218D01*
G37*
G36*
G01X718724D02*
X718882Y272604D01*
X718875Y272697D01*
X718850Y272738D01*
G02X717608Y277204I7411J4467D01*
G02X726261Y285856I8653J-1D01*
G02X733430Y282049I1J-8652D01*
G01X733458Y282008D01*
X733545Y281961D01*
X733977D01*
X734064Y282008D01*
X734092Y282049D01*
G02X741261Y285856I7168J-4845D01*
G02Y268552I0J-8652D01*
G02X734092Y272359I-1J8652D01*
G01X734064Y272400D01*
X733977Y272447D01*
X733545D01*
X733458Y272400D01*
X733430Y272359D01*
G02X726261Y268552I-7168J4845D01*
G02X725337Y268601I-4J8652D01*
G01X725289Y268606D01*
X725202Y268574D01*
X724918Y268268D01*
X724892Y268178D01*
X724901Y268131D01*
G02X724986Y267204I-5018J-928D01*
G02X714780I-5103J0D01*
G02X718607Y272144I5102J0D01*
G01X718654Y272157D01*
X718724Y272218D01*
G37*
G36*
G01X274082Y284635D02*
G02X277219Y286580I3137J-1557D01*
G02X279111Y286026I2J-3502D01*
G03X279327I108J168D01*
G02X281219Y286580I1890J-2948D01*
G02X283111Y286026I2J-3502D01*
G03X283327I108J168D01*
G02X285219Y286580I1890J-2948D01*
G02X288722Y283078I1J-3502D01*
G02X288167Y281186I-3502J0D01*
G03Y280970I168J-108D01*
G02Y277186I-2947J-1892D01*
G03Y276970I168J-108D01*
G02Y273186I-2947J-1892D01*
G03Y272970I168J-108D01*
G02X288722Y271078I-2947J-1892D01*
G02X285219Y267576I-3503J1D01*
G02X283327Y268130I-2J3502D01*
G03X283111I-108J-168D01*
G02X281219Y267576I-1890J2948D01*
G02X279327Y268130I-2J3502D01*
G03X279111I-108J-168D01*
G02X277219Y267576I-1890J2948D01*
G02X274001Y269696I0J3502D01*
G01X273983Y269736D01*
X273919Y269795D01*
X273544Y269911D01*
X273458Y269900D01*
X273421Y269877D01*
G02X268819Y268552I-4601J7327D01*
G02X261650Y272359I-1J8652D01*
G01X261622Y272400D01*
X261535Y272447D01*
X261103D01*
X261016Y272400D01*
X260988Y272359D01*
G02X253819Y268552I-7168J4845D01*
G02X252895Y268601I-4J8652D01*
G01X252847Y268606D01*
X252760Y268574D01*
X252476Y268268D01*
X252450Y268178D01*
X252459Y268131D01*
G02X252544Y267204I-5018J-928D01*
G02X242338I-5103J0D01*
G02X246165Y272144I5102J0D01*
G01X246212Y272157D01*
X246282Y272218D01*
X246440Y272604D01*
X246433Y272697D01*
X246408Y272738D01*
G02X245166Y277204I7411J4467D01*
G02X253819Y285856I8653J-1D01*
G02X260988Y282049I1J-8652D01*
G01X261016Y282008D01*
X261103Y281961D01*
X261535D01*
X261622Y282008D01*
X261650Y282049D01*
G02X268819Y285856I7168J-4845D01*
G02X273507Y284477I2J-8652D01*
G01X273543Y284453D01*
X273626Y284440D01*
X273998Y284543D01*
X274062Y284596D01*
X274082Y284635D01*
G37*
G36*
G01X431368Y284755D02*
G02X434499Y286688I3131J-1569D01*
G02X436391Y286134I2J-3502D01*
G03X436607I108J168D01*
G02X438499Y286688I1890J-2948D01*
G02X440391Y286134I2J-3502D01*
G03X440607I108J168D01*
G02X442499Y286688I1890J-2948D01*
G02X446002Y283186I1J-3502D01*
G02X445447Y281294I-3502J0D01*
G03Y281078I168J-108D01*
G02Y277294I-2947J-1892D01*
G03Y277078I168J-108D01*
G02Y273294I-2947J-1892D01*
G03Y273078I168J-108D01*
G02X446002Y271186I-2947J-1892D01*
G02X442499Y267684I-3503J1D01*
G02X440607Y268238I-2J3502D01*
G03X440391I-108J-168D01*
G02X438499Y267684I-1890J2948D01*
G02X436607Y268238I-2J3502D01*
G03X436391I-108J-168D01*
G02X434499Y267684I-1890J2948D01*
G02X431355Y269642I0J3503D01*
G01X431337Y269680D01*
X431272Y269734D01*
X430908Y269840D01*
X430825Y269829D01*
X430789Y269807D01*
G02X426299Y268552I-4488J7398D01*
G02X419130Y272359I-1J8652D01*
G01X419102Y272400D01*
X419015Y272447D01*
X418583D01*
X418496Y272400D01*
X418468Y272359D01*
G02X411299Y268552I-7168J4845D01*
G02X410375Y268601I-4J8652D01*
G01X410327Y268606D01*
X410240Y268574D01*
X409956Y268268D01*
X409930Y268178D01*
X409939Y268131D01*
G02X410024Y267204I-5018J-928D01*
G02X399818I-5103J0D01*
G02X403645Y272144I5102J0D01*
G01X403692Y272157D01*
X403762Y272218D01*
X403920Y272604D01*
X403913Y272697D01*
X403888Y272738D01*
G02X402646Y277204I7411J4467D01*
G02X411299Y285856I8653J-1D01*
G02X418468Y282049I1J-8652D01*
G01X418496Y282008D01*
X418583Y281961D01*
X419015D01*
X419102Y282008D01*
X419130Y282049D01*
G02X426299Y285856I7168J-4845D01*
G02X430802Y284593I2J-8652D01*
G01X430838Y284570D01*
X430920Y284559D01*
X431285Y284664D01*
X431348Y284717D01*
X431368Y284755D01*
G37*
G36*
G01X43435Y289857D02*
G02X38780Y287196I-4655J2741D01*
G02X33378Y292598I0J5402D01*
G02X34447Y295825I5402J1D01*
G03Y296064I-160J120D01*
G02X33378Y299291I4333J3226D01*
G02X38780Y304694I5402J1D01*
G02X43435Y302032I-1J-5403D01*
G01X43462Y301986D01*
X43554Y301934D01*
X44006D01*
X44098Y301986D01*
X44125Y302032D01*
G02X48780Y304694I4656J-2741D01*
G02X54182Y299291I-1J-5403D01*
G02X53113Y296064I-5402J-1D01*
G03Y295825I160J-119D01*
G02X54182Y292598I-4333J-3226D01*
G02X48780Y287196I-5402J0D01*
G02X44125Y289857I0J5402D01*
G01X44098Y289903D01*
X44006Y289955D01*
X43554D01*
X43462Y289903D01*
X43435Y289857D01*
G37*
G36*
G01X1064581Y308702D02*
G02X1066000Y309002I1418J-3202D01*
G02X1067419Y308702I1J-3502D01*
G03X1067581I81J183D01*
G02X1069000Y309002I1418J-3202D01*
G02X1070419Y308702I1J-3502D01*
G03X1070581I81J183D01*
G02X1072000Y309002I1418J-3202D01*
G02X1075502Y305500I0J-3502D01*
G02X1075202Y304081I-3502J-1D01*
G03Y303919I183J-81D01*
G02X1075502Y302500I-3202J-1418D01*
G02X1072000Y298998I-3502J0D01*
G02X1070581Y299298I-1J3502D01*
G03X1070419I-81J-183D01*
G02X1069611Y299051I-1420J3202D01*
G03X1069449Y298889I35J-197D01*
G02X1069202Y298081I-3449J612D01*
G03Y297919I183J-81D01*
G02X1069449Y297111I-3202J-1420D01*
G03X1069611Y296949I197J35D01*
G02X1070419Y296702I-612J-3449D01*
G03X1070581I81J183D01*
G02X1072000Y297002I1418J-3202D01*
G02X1075502Y293500I0J-3502D01*
G02X1075202Y292081I-3502J-1D01*
G03Y291919I183J-81D01*
G02X1075502Y290500I-3202J-1418D01*
G02X1072000Y286998I-3502J0D01*
G02X1070581Y287298I-1J3502D01*
G03X1070419I-81J-183D01*
G02X1069000Y286998I-1418J3202D01*
G02X1067581Y287298I-1J3502D01*
G03X1067419I-81J-183D01*
G02X1066000Y286998I-1418J3202D01*
G02X1064581Y287298I-1J3502D01*
G03X1064419I-81J-183D01*
G02X1063000Y286998I-1418J3202D01*
G02X1061581Y287298I-1J3502D01*
G03X1061419I-81J-183D01*
G02X1060000Y286998I-1418J3202D01*
G02X1056498Y290500I0J3502D01*
G02X1056798Y291919I3502J1D01*
G03Y292081I-183J81D01*
G02X1056498Y293500I3202J1418D01*
G02X1056798Y294919I3502J1D01*
G03Y295081I-183J81D01*
G02X1056498Y296500I3202J1418D01*
G02X1056798Y297919I3502J1D01*
G03Y298081I-183J81D01*
G02X1056498Y299500I3202J1418D01*
G02X1056798Y300919I3502J1D01*
G03Y301081I-183J81D01*
G02X1056498Y302500I3202J1418D01*
G02X1056798Y303919I3502J1D01*
G03Y304081I-183J81D01*
G02X1056498Y305500I3202J1418D01*
G02X1060000Y309002I3502J0D01*
G02X1061419Y308702I1J-3502D01*
G03X1061581I81J183D01*
G02X1063000Y309002I1418J-3202D01*
G02X1064419Y308702I1J-3502D01*
G03X1064581I81J183D01*
G37*
G36*
G01X1059200Y356470D02*
X1059308Y356917D01*
X1059276Y357021D01*
X1059236Y357058D01*
G02X1058098Y359642I2365J2584D01*
G02X1065102I3502J0D01*
G02X1063920Y357018I-3502J-1D01*
G01X1063879Y356982D01*
X1063845Y356880D01*
X1063940Y356433D01*
X1064011Y356354D01*
X1064063Y356337D01*
G02X1064419Y356202I-1062J-3337D01*
G03X1064581I81J183D01*
G02X1066000Y356502I1418J-3202D01*
G02X1067419Y356202I1J-3502D01*
G03X1067581I81J183D01*
G02X1069000Y356502I1418J-3202D01*
G02X1070419Y356202I1J-3502D01*
G03X1070581I81J183D01*
G02X1072000Y356502I1418J-3202D01*
G02X1075502Y353000I0J-3502D01*
G02X1075202Y351581I-3502J-1D01*
G03Y351419I183J-81D01*
G02X1075502Y350000I-3202J-1418D01*
G02X1072000Y346498I-3502J0D01*
G02X1070581Y346798I-1J3502D01*
G03X1070419I-81J-183D01*
G02X1069611Y346551I-1420J3202D01*
G03X1069449Y346389I35J-197D01*
G02X1069202Y345581I-3449J612D01*
G03Y345419I183J-81D01*
G02X1069449Y344611I-3202J-1420D01*
G03X1069611Y344449I197J35D01*
G02X1070419Y344202I-612J-3449D01*
G03X1070581I81J183D01*
G02X1072000Y344502I1418J-3202D01*
G02X1075502Y341000I0J-3502D01*
G02X1075202Y339581I-3502J-1D01*
G03Y339419I183J-81D01*
G02X1075502Y338000I-3202J-1418D01*
G02X1072000Y334498I-3502J0D01*
G02X1070581Y334798I-1J3502D01*
G03X1070419I-81J-183D01*
G02X1069000Y334498I-1418J3202D01*
G02X1067581Y334798I-1J3502D01*
G03X1067419I-81J-183D01*
G02X1066000Y334498I-1418J3202D01*
G02X1064581Y334798I-1J3502D01*
G03X1064419I-81J-183D01*
G02X1063000Y334498I-1418J3202D01*
G02X1061581Y334798I-1J3502D01*
G03X1061419I-81J-183D01*
G02X1060000Y334498I-1418J3202D01*
G02X1056498Y338000I0J3502D01*
G02X1056798Y339419I3502J1D01*
G03Y339581I-183J81D01*
G02X1056498Y341000I3202J1418D01*
G02X1056798Y342419I3502J1D01*
G03Y342581I-183J81D01*
G02X1056498Y344000I3202J1418D01*
G02X1056798Y345419I3502J1D01*
G03Y345581I-183J81D01*
G02X1056498Y347000I3202J1418D01*
G02X1056798Y348419I3502J1D01*
G03Y348581I-183J81D01*
G02X1056498Y350000I3202J1418D01*
G02X1056798Y351419I3502J1D01*
G03Y351581I-183J81D01*
G02X1056498Y353000I3202J1418D01*
G02X1059072Y356377I3502J0D01*
G01X1059125Y356392D01*
X1059200Y356470D01*
G37*
G36*
G01X946985Y388121D02*
X947372D01*
X947450Y388156D01*
X947479Y388189D01*
G02X950110Y389380I2632J-2312D01*
G02X951529Y389079I-2J-3503D01*
G03X951691I81J183D01*
G02X953110Y389380I1421J-3202D01*
G02Y382374I0J-3503D01*
G02X951691Y382675I2J3503D01*
G03X951529I-81J-183D01*
G02X950110Y382374I-1421J3202D01*
G02X947479Y383565I1J3503D01*
G01X947450Y383598D01*
X947372Y383633D01*
X946985D01*
X946907Y383598D01*
X946878Y383565D01*
G02X944247Y382374I-2632J2312D01*
G02X942828Y382675I2J3503D01*
G03X942666I-81J-183D01*
G02X941247Y382374I-1421J3202D01*
G02X938162Y384219I0J3502D01*
G01X938135Y384269D01*
X938039Y384325D01*
X937571Y384318D01*
X937477Y384259D01*
X937452Y384208D01*
G02X934317Y382268I-3135J1563D01*
G02X932898Y382569I2J3503D01*
G03X932736I-81J-183D01*
G02X931317Y382268I-1421J3202D01*
G02X928686Y383459I1J3503D01*
G01X928657Y383492D01*
X928579Y383527D01*
X928192D01*
X928114Y383492D01*
X928085Y383459D01*
G02X925454Y382268I-2632J2312D01*
G02X924035Y382569I2J3503D01*
G03X923873I-81J-183D01*
G02X922454Y382268I-1421J3202D01*
G02X919320Y384207I0J3502D01*
G01X919295Y384258D01*
X919201Y384317D01*
X918732Y384324D01*
X918637Y384268D01*
X918610Y384218D01*
G02X915525Y382374I-3085J1659D01*
G02X914106Y382675I2J3503D01*
G03X913944I-81J-183D01*
G02X912525Y382374I-1421J3202D01*
G02X909894Y383565I1J3503D01*
G01X909865Y383598D01*
X909787Y383633D01*
X909400D01*
X909322Y383598D01*
X909293Y383565D01*
G02X906662Y382374I-2632J2312D01*
G02X905243Y382675I2J3503D01*
G03X905081I-81J-183D01*
G02X903662Y382374I-1421J3202D01*
G02Y389380I0J3503D01*
G02X905081Y389079I-2J-3503D01*
G03X905243I81J183D01*
G02X906662Y389380I1421J-3202D01*
G02X909293Y388189I-1J-3503D01*
G01X909322Y388156D01*
X909400Y388121D01*
X909787D01*
X909865Y388156D01*
X909894Y388189D01*
G02X912525Y389380I2632J-2312D01*
G02X913944Y389079I-2J-3503D01*
G03X914106I81J183D01*
G02X915525Y389380I1421J-3202D01*
G02X918659Y387441I0J-3502D01*
G01X918684Y387390D01*
X918778Y387331D01*
X919247Y387324D01*
X919342Y387380D01*
X919369Y387430D01*
G02X922454Y389274I3085J-1659D01*
G02X923873Y388973I-2J-3503D01*
G03X924035I81J183D01*
G02X925454Y389274I1421J-3202D01*
G02X928085Y388083I-1J-3503D01*
G01X928114Y388050D01*
X928192Y388015D01*
X928579D01*
X928657Y388050D01*
X928686Y388083D01*
G02X931317Y389274I2632J-2312D01*
G02X932736Y388973I-2J-3503D01*
G03X932898I81J183D01*
G02X934317Y389274I1421J-3202D01*
G02X937402Y387429I0J-3502D01*
G01X937429Y387379D01*
X937525Y387323D01*
X937993Y387330D01*
X938087Y387389D01*
X938112Y387440D01*
G02X941247Y389380I3135J-1563D01*
G02X942666Y389079I-2J-3503D01*
G03X942828I81J183D01*
G02X944247Y389380I1421J-3202D01*
G02X946878Y388189I-1J-3503D01*
G01X946907Y388156D01*
X946985Y388121D01*
G37*
G36*
G01X853128Y388122D02*
X853515D01*
X853593Y388157D01*
X853622Y388190D01*
G02X856253Y389380I2630J-2312D01*
G02X857672Y389080I1J-3502D01*
G03X857834I81J183D01*
G02X859253Y389380I1418J-3202D01*
G02X862110Y387903I0J-3502D01*
G01X862138Y387864D01*
X862222Y387820D01*
X862641Y387813D01*
X862726Y387854D01*
X862755Y387892D01*
G02X865542Y389274I2788J-2121D01*
G02X866961Y388973I-2J-3503D01*
G03X867123I81J183D01*
G02X868542Y389274I1421J-3202D01*
G02X871173Y388083I-1J-3503D01*
G01X871202Y388050D01*
X871280Y388015D01*
X871667D01*
X871745Y388050D01*
X871774Y388083D01*
G02X874405Y389274I2632J-2312D01*
G02X875824Y388973I-2J-3503D01*
G03X875986I81J183D01*
G02X877405Y389274I1421J-3202D01*
G02X880467Y387472I0J-3503D01*
G03X880642Y387369I175J97D01*
G01X880991D01*
G03X881166Y387472I0J200D01*
G02X884228Y389274I3062J-1701D01*
G02X885647Y388973I-2J-3503D01*
G03X885809I81J183D01*
G02X887228Y389274I1421J-3202D01*
G02X889859Y388083I-1J-3503D01*
G01X889888Y388050D01*
X889966Y388015D01*
X890353D01*
X890431Y388050D01*
X890460Y388083D01*
G02X893091Y389274I2632J-2312D01*
G02X894510Y388973I-2J-3503D01*
G03X894672I81J183D01*
G02X896091Y389274I1421J-3202D01*
G02Y382268I0J-3503D01*
G02X894672Y382569I2J3503D01*
G03X894510I-81J-183D01*
G02X893091Y382268I-1421J3202D01*
G02X890460Y383459I1J3503D01*
G01X890431Y383492D01*
X890353Y383527D01*
X889966D01*
X889888Y383492D01*
X889859Y383459D01*
G02X887228Y382268I-2632J2312D01*
G02X885809Y382569I2J3503D01*
G03X885647I-81J-183D01*
G02X884228Y382268I-1421J3202D01*
G02X881166Y384070I0J3503D01*
G03X880991Y384173I-175J-97D01*
G01X880642D01*
G03X880467Y384070I0J-200D01*
G02X877405Y382268I-3062J1701D01*
G02X875986Y382569I2J3503D01*
G03X875824I-81J-183D01*
G02X874405Y382268I-1421J3202D01*
G02X871774Y383459I1J3503D01*
G01X871745Y383492D01*
X871667Y383527D01*
X871280D01*
X871202Y383492D01*
X871173Y383459D01*
G02X868542Y382268I-2632J2312D01*
G02X867123Y382569I2J3503D01*
G03X866961I-81J-183D01*
G02X865542Y382268I-1421J3202D01*
G02X862685Y383746I1J3502D01*
G01X862657Y383785D01*
X862573Y383829D01*
X862154Y383836D01*
X862069Y383795D01*
X862040Y383757D01*
G02X859253Y382376I-2787J2122D01*
G02X857834Y382676I-1J3502D01*
G03X857672I-81J-183D01*
G02X856253Y382376I-1418J3202D01*
G02X853622Y383566I-1J3502D01*
G01X853593Y383599D01*
X853515Y383634D01*
X853128D01*
X853050Y383599D01*
X853021Y383566D01*
G02X850390Y382376I-2630J2312D01*
G02X848971Y382676I-1J3502D01*
G03X848809I-81J-183D01*
G02X847390Y382376I-1418J3202D01*
G02Y389380I0J3502D01*
G02X848809Y389080I1J-3502D01*
G03X848971I81J183D01*
G02X850390Y389380I1418J-3202D01*
G02X853021Y388190I1J-3502D01*
G01X853050Y388157D01*
X853128Y388122D01*
G37*
G36*
G01X1071582Y404036D02*
X1071738Y404469D01*
X1071718Y404575D01*
X1071682Y404617D01*
G02X1070814Y406925I2634J2308D01*
G02X1077818I3502J0D01*
G02X1074872Y403467I-3502J0D01*
G01X1074817Y403458D01*
X1074734Y403389D01*
X1074578Y402956D01*
X1074598Y402850D01*
X1074634Y402808D01*
G02X1075502Y400500I-2634J-2308D01*
G02X1075202Y399081I-3502J-1D01*
G03Y398919I183J-81D01*
G02X1075502Y397500I-3202J-1418D01*
G02X1072000Y393998I-3502J0D01*
G02X1070581Y394298I-1J3502D01*
G03X1070419I-81J-183D01*
G02X1069611Y394051I-1420J3202D01*
G03X1069449Y393889I35J-197D01*
G02X1069202Y393081I-3449J612D01*
G03Y392919I183J-81D01*
G02X1069449Y392111I-3202J-1420D01*
G03X1069611Y391949I197J35D01*
G02X1070419Y391702I-612J-3449D01*
G03X1070581I81J183D01*
G02X1072000Y392002I1418J-3202D01*
G02X1075502Y388500I0J-3502D01*
G02X1075202Y387081I-3502J-1D01*
G03Y386919I183J-81D01*
G02X1075502Y385500I-3202J-1418D01*
G02X1072000Y381998I-3502J0D01*
G02X1070581Y382298I-1J3502D01*
G03X1070419I-81J-183D01*
G02X1069000Y381998I-1418J3202D01*
G02X1067581Y382298I-1J3502D01*
G03X1067419I-81J-183D01*
G02X1066000Y381998I-1418J3202D01*
G02X1064581Y382298I-1J3502D01*
G03X1064419I-81J-183D01*
G02X1063000Y381998I-1418J3202D01*
G02X1061581Y382298I-1J3502D01*
G03X1061419I-81J-183D01*
G02X1060000Y381998I-1418J3202D01*
G02X1056498Y385500I0J3502D01*
G02X1056798Y386919I3502J1D01*
G03Y387081I-183J81D01*
G02X1056498Y388500I3202J1418D01*
G02X1056798Y389919I3502J1D01*
G03Y390081I-183J81D01*
G02X1056498Y391500I3202J1418D01*
G02X1056798Y392919I3502J1D01*
G03Y393081I-183J81D01*
G02X1056498Y394500I3202J1418D01*
G02X1056798Y395919I3502J1D01*
G03Y396081I-183J81D01*
G02X1056498Y397500I3202J1418D01*
G02X1056798Y398919I3502J1D01*
G03Y399081I-183J81D01*
G02X1056498Y400500I3202J1418D01*
G02X1060000Y404002I3502J0D01*
G02X1061419Y403702I1J-3502D01*
G03X1061581I81J183D01*
G02X1063000Y404002I1418J-3202D01*
G02X1064419Y403702I1J-3502D01*
G03X1064581I81J183D01*
G02X1066000Y404002I1418J-3202D01*
G02X1067419Y403702I1J-3502D01*
G03X1067581I81J183D01*
G02X1069000Y404002I1418J-3202D01*
G02X1070419Y403702I1J-3502D01*
G03X1070581I81J183D01*
G02X1071444Y403958I1419J-3202D01*
G01X1071499Y403967D01*
X1071582Y404036D01*
G37*
G36*
G01X806904Y420118D02*
G02X808323Y420418I1418J-3202D01*
G02X809742Y420118I1J-3502D01*
G03X809904I81J183D01*
G02X811323Y420418I1418J-3202D01*
G02X812742Y420118I1J-3502D01*
G03X812904I81J183D01*
G02X814323Y420418I1418J-3202D01*
G02X815723Y420126I0J-3502D01*
G03X815876Y420123I80J184D01*
G02X817153Y420364I1277J-3261D01*
G02X820656Y416862I1J-3502D01*
G02X820355Y415443I-3503J2D01*
G03Y415281I183J-81D01*
G02X820656Y413862I-3202J-1421D01*
G02X820402Y412554I-3503J2D01*
G03Y412404I186J-75D01*
G02X820656Y411096I-3249J-1310D01*
G02X820355Y409677I-3503J2D01*
G03Y409515I183J-81D01*
G02X820656Y408096I-3202J-1421D01*
G02X820355Y406677I-3503J2D01*
G03Y406515I183J-81D01*
G02X820656Y405096I-3202J-1421D01*
G02X817153Y401594I-3503J1D01*
G02X815753Y401886I0J3502D01*
G03X815600Y401889I-80J-184D01*
G02X814323Y401648I-1277J3261D01*
G02X812904Y401948I-1J3502D01*
G03X812742I-81J-183D01*
G02X811323Y401648I-1418J3202D01*
G02X809904Y401948I-1J3502D01*
G03X809742I-81J-183D01*
G02X808323Y401648I-1418J3202D01*
G02X806904Y401948I-1J3502D01*
G03X806742I-81J-183D01*
G02X805323Y401648I-1418J3202D01*
G02X803904Y401948I-1J3502D01*
G03X803742I-81J-183D01*
G02X802323Y401648I-1418J3202D01*
G02X800904Y401948I-1J3502D01*
G03X800742I-81J-183D01*
G02X799323Y401648I-1418J3202D01*
G02X798098Y401869I-1J3502D01*
G03X797951Y401866I-70J-188D01*
G02X796600Y401594I-1353J3231D01*
G02X793098Y405097I1J3503D01*
G02X793398Y406516I3502J1D01*
G03Y406678I-183J81D01*
G02X793098Y408097I3202J1418D01*
G02X793398Y409516I3502J1D01*
G03Y409678I-183J81D01*
G02X793098Y411097I3202J1418D01*
G02X793351Y412405I3502J1D01*
G03Y412555I-186J75D01*
G02X793098Y413863I3249J1307D01*
G02X793398Y415282I3502J1D01*
G03Y415444I-183J81D01*
G02X793098Y416863I3202J1418D01*
G02X796600Y420366I3502J1D01*
G02X797825Y420144I-2J-3503D01*
G03X797972Y420147I70J188D01*
G02X799323Y420418I1351J-3232D01*
G02X800742Y420118I1J-3502D01*
G03X800904I81J183D01*
G02X802323Y420418I1418J-3202D01*
G02X803742Y420118I1J-3502D01*
G03X803904I81J183D01*
G02X805323Y420418I1418J-3202D01*
G02X806742Y420118I1J-3502D01*
G03X806904I81J183D01*
G37*
G36*
G01X863923D02*
G02X865342Y420418I1418J-3202D01*
G02X866761Y420118I1J-3502D01*
G03X866923I81J183D01*
G02X868342Y420418I1418J-3202D01*
G02X869761Y420118I1J-3502D01*
G03X869923I81J183D01*
G02X871342Y420418I1418J-3202D01*
G02X872742Y420126I0J-3502D01*
G03X872895Y420123I80J184D01*
G02X874172Y420364I1277J-3261D01*
G02X877674Y416862I0J-3502D01*
G02X877374Y415443I-3502J-1D01*
G03Y415281I183J-81D01*
G02X877674Y413862I-3202J-1418D01*
G02X877421Y412554I-3502J-1D01*
G03Y412404I186J-75D01*
G02X877674Y411096I-3249J-1307D01*
G02X877374Y409677I-3502J-1D01*
G03Y409515I183J-81D01*
G02X877674Y408096I-3202J-1418D01*
G02X877374Y406677I-3502J-1D01*
G03Y406515I183J-81D01*
G02X877674Y405096I-3202J-1418D01*
G02X874172Y401594I-3502J0D01*
G02X872772Y401886I0J3502D01*
G03X872619Y401889I-80J-184D01*
G02X871342Y401648I-1277J3261D01*
G02X869923Y401948I-1J3502D01*
G03X869761I-81J-183D01*
G02X868342Y401648I-1418J3202D01*
G02X866923Y401948I-1J3502D01*
G03X866761I-81J-183D01*
G02X865342Y401648I-1418J3202D01*
G02X863923Y401948I-1J3502D01*
G03X863761I-81J-183D01*
G02X862342Y401648I-1418J3202D01*
G02X860923Y401948I-1J3502D01*
G03X860761I-81J-183D01*
G02X859342Y401648I-1418J3202D01*
G02X857923Y401948I-1J3502D01*
G03X857761I-81J-183D01*
G02X856342Y401648I-1418J3202D01*
G02X855117Y401869I-1J3502D01*
G03X854970Y401866I-70J-188D01*
G02X853619Y401594I-1353J3231D01*
G02X850116Y405097I0J3503D01*
G02X850417Y406516I3503J-2D01*
G03Y406678I-183J81D01*
G02X850116Y408097I3202J1421D01*
G02X850417Y409516I3503J-2D01*
G03Y409678I-183J81D01*
G02X850116Y411097I3202J1421D01*
G02X850370Y412405I3503J-2D01*
G03Y412555I-186J75D01*
G02X850116Y413863I3249J1310D01*
G02X850417Y415282I3503J-2D01*
G03Y415444I-183J81D01*
G02X850116Y416863I3202J1421D01*
G02X853619Y420366I3503J0D01*
G02X854844Y420144I-2J-3503D01*
G03X854991Y420147I70J188D01*
G02X856342Y420418I1351J-3232D01*
G02X857761Y420118I1J-3502D01*
G03X857923I81J183D01*
G02X859342Y420418I1418J-3202D01*
G02X860761Y420118I1J-3502D01*
G03X860923I81J183D01*
G02X862342Y420418I1418J-3202D01*
G02X863761Y420118I1J-3502D01*
G03X863923I81J183D01*
G37*
G36*
G01X112520Y422234D02*
G02X112198Y423700I3180J1467D01*
G02X112498Y425119I3502J1D01*
G03Y425281I-182J81D01*
G02X112198Y426700I3202J1418D01*
G02X115700Y430202I3502J0D01*
G02X117576Y429657I0J-3501D01*
G03X117782Y429651I108J169D01*
G02X119500Y430102I1719J-3051D01*
G02X121155Y429686I0J-3502D01*
G03X121345I95J176D01*
G02X123000Y430102I1655J-3086D01*
G02X126502Y426600I0J-3502D01*
G02X126202Y425181I-3502J-1D01*
G03Y425019I182J-81D01*
G02X126502Y423600I-3202J-1418D01*
G02X126181Y422134I-3502J-1D01*
G03Y421967I181J-84D01*
G02X126502Y420500I-3181J-1465D01*
G02X126202Y419081I-3502J-1D01*
G03Y418919I183J-81D01*
G02X126502Y417500I-3202J-1418D01*
G02X126202Y416081I-3502J-1D01*
G03Y415919I183J-81D01*
G02X126502Y414500I-3202J-1418D01*
G02X126202Y413081I-3502J-1D01*
G03Y412919I183J-81D01*
G02X126502Y411500I-3202J-1418D01*
G02X126202Y410081I-3502J-1D01*
G03Y409919I183J-81D01*
G02X126502Y408500I-3202J-1418D01*
G02X123000Y404998I-3502J0D01*
G02X121345Y405413I-1J3502D01*
G03X121155I-95J-176D01*
G02X119500Y404998I-1654J3087D01*
G02X117623Y405543I-1J3502D01*
G03X117418Y405548I-107J-169D01*
G02X115700Y405098I-1717J3052D01*
G02X112198Y408600I0J3502D01*
G02X112498Y410019I3502J1D01*
G03Y410181I-182J81D01*
G02X112198Y411600I3202J1418D01*
G02X112498Y413019I3502J1D01*
G03Y413181I-182J81D01*
G02X112198Y414600I3202J1418D01*
G02X112498Y416019I3502J1D01*
G03Y416181I-182J81D01*
G02X112198Y417600I3202J1418D01*
G02X112498Y419019I3502J1D01*
G03Y419181I-182J81D01*
G02X112198Y420600I3202J1418D01*
G02X112520Y422066I3502J-1D01*
G03Y422234I-182J84D01*
G37*
G36*
G01X153598Y425181D02*
G02X153298Y426600I3202J1418D01*
G02X156800Y430102I3502J0D01*
G02X158455Y429686I0J-3502D01*
G03X158645I95J176D01*
G02X160300Y430102I1655J-3086D01*
G02X161867Y429732I0J-3503D01*
G03X162056Y429737I90J179D01*
G02X163800Y430202I1744J-3038D01*
G02X167302Y426700I0J-3502D01*
G02X167002Y425281I-3502J-1D01*
G03Y425119I182J-81D01*
G02X167302Y423700I-3202J-1418D01*
G02X167067Y422438I-3502J-1D01*
G03X167078Y422271I187J-72D01*
G02X167502Y420600I-3078J-1670D01*
G02X167202Y419181I-3502J-1D01*
G03Y419019I182J-81D01*
G02X167502Y417600I-3202J-1418D01*
G02X167202Y416181I-3502J-1D01*
G03Y416019I182J-81D01*
G02X167502Y414600I-3202J-1418D01*
G02X167202Y413181I-3502J-1D01*
G03Y413019I182J-81D01*
G02X167502Y411600I-3202J-1418D01*
G02X167202Y410181I-3502J-1D01*
G03Y410019I182J-81D01*
G02X167502Y408600I-3202J-1418D01*
G02X164000Y405098I-3502J0D01*
G02X162433Y405468I0J3503D01*
G03X162244Y405463I-90J-179D01*
G02X160500Y404998I-1744J3038D01*
G02X158845Y405413I-1J3502D01*
G03X158655I-95J-176D01*
G02X157000Y404998I-1654J3087D01*
G02X153498Y408500I0J3502D01*
G02X153798Y409919I3502J1D01*
G03Y410081I-183J81D01*
G02X153498Y411500I3202J1418D01*
G02X153798Y412919I3502J1D01*
G03Y413081I-183J81D01*
G02X153498Y414500I3202J1418D01*
G02X153798Y415919I3502J1D01*
G03Y416081I-183J81D01*
G02X153498Y417500I3202J1418D01*
G02X153798Y418919I3502J1D01*
G03Y419081I-183J81D01*
G02X153498Y420500I3202J1418D01*
G02X153733Y421762I3502J1D01*
G03X153722Y421930I-187J72D01*
G02X153298Y423600I3077J1670D01*
G02X153598Y425019I3502J1D01*
G03Y425181I-182J81D01*
G37*
G36*
G01X563318Y445297D02*
G02X564500Y445502I1181J-3297D01*
G02Y438498I0J-3502D01*
G02X563318Y438703I-1J3502D01*
G03X563182I-68J-188D01*
G02X562000Y438498I-1181J3297D01*
G02Y445502I0J3502D01*
G02X563182Y445297I1J-3502D01*
G03X563318I68J188D01*
G37*
G36*
G01X1064581Y451202D02*
G02X1066000Y451502I1418J-3202D01*
G02X1067419Y451202I1J-3502D01*
G03X1067581I81J183D01*
G02X1069000Y451502I1418J-3202D01*
G02X1070419Y451202I1J-3502D01*
G03X1070581I81J183D01*
G02X1072000Y451502I1418J-3202D01*
G02X1075502Y448000I0J-3502D01*
G02X1075202Y446581I-3502J-1D01*
G03Y446419I183J-81D01*
G02X1075502Y445000I-3202J-1418D01*
G02X1072000Y441498I-3502J0D01*
G02X1070581Y441798I-1J3502D01*
G03X1070419I-81J-183D01*
G02X1069611Y441551I-1420J3202D01*
G03X1069449Y441389I35J-197D01*
G02X1069202Y440581I-3449J612D01*
G03Y440419I183J-81D01*
G02X1069449Y439611I-3202J-1420D01*
G03X1069611Y439449I197J35D01*
G02X1070419Y439202I-612J-3449D01*
G03X1070581I81J183D01*
G02X1072000Y439502I1418J-3202D01*
G02X1075502Y436000I0J-3502D01*
G02X1075202Y434581I-3502J-1D01*
G03Y434419I183J-81D01*
G02X1075502Y433000I-3202J-1418D01*
G02X1072000Y429498I-3502J0D01*
G02X1070581Y429798I-1J3502D01*
G03X1070419I-81J-183D01*
G02X1069000Y429498I-1418J3202D01*
G02X1067581Y429798I-1J3502D01*
G03X1067419I-81J-183D01*
G02X1066000Y429498I-1418J3202D01*
G02X1064581Y429798I-1J3502D01*
G03X1064419I-81J-183D01*
G02X1063000Y429498I-1418J3202D01*
G02X1061581Y429798I-1J3502D01*
G03X1061419I-81J-183D01*
G02X1060000Y429498I-1418J3202D01*
G02X1056498Y433000I0J3502D01*
G02X1056798Y434419I3502J1D01*
G03Y434581I-183J81D01*
G02X1056498Y436000I3202J1418D01*
G02X1056798Y437419I3502J1D01*
G03Y437581I-183J81D01*
G02X1056498Y439000I3202J1418D01*
G02X1056798Y440419I3502J1D01*
G03Y440581I-183J81D01*
G02X1056498Y442000I3202J1418D01*
G02X1056798Y443419I3502J1D01*
G03Y443581I-183J81D01*
G02X1056498Y445000I3202J1418D01*
G02X1056798Y446419I3502J1D01*
G03Y446581I-183J81D01*
G02X1056498Y448000I3202J1418D01*
G02X1060000Y451502I3502J0D01*
G02X1061419Y451202I1J-3502D01*
G03X1061581I81J183D01*
G02X1063000Y451502I1418J-3202D01*
G02X1064419Y451202I1J-3502D01*
G03X1064581I81J183D01*
G37*
G36*
G01X810290Y489534D02*
G02X811709Y489834I1418J-3202D01*
G02X813128Y489534I1J-3502D01*
G03X813290I81J183D01*
G02X814709Y489834I1418J-3202D01*
G02X816128Y489534I1J-3502D01*
G03X816290I81J183D01*
G02X817709Y489834I1418J-3202D01*
G02X821212Y486332I1J-3502D01*
G02X820920Y484932I-3502J0D01*
G03X820917Y484779I183J-80D01*
G02X821158Y483503I-3262J-1277D01*
G02X820857Y482084I-3503J2D01*
G03Y481922I183J-81D01*
G02X821158Y480503I-3202J-1421D01*
G02X820894Y479170I-3503J1D01*
G03Y479017I185J-76D01*
G02X821158Y477684I-3239J-1334D01*
G02X820857Y476265I-3503J2D01*
G03Y476103I183J-81D01*
G02X821158Y474684I-3202J-1421D01*
G02X817655Y471182I-3503J1D01*
G02X816236Y471482I-1J3502D01*
G03X816074I-81J-183D01*
G02X814655Y471182I-1418J3202D01*
G02X813236Y471482I-1J3502D01*
G03X813074I-81J-183D01*
G02X811655Y471182I-1418J3202D01*
G02X810236Y471482I-1J3502D01*
G03X810074I-81J-183D01*
G02X808655Y471182I-1418J3202D01*
G02X807236Y471482I-1J3502D01*
G03X807074I-81J-183D01*
G02X805655Y471182I-1418J3202D01*
G02X804236Y471482I-1J3502D01*
G03X804074I-81J-183D01*
G02X802655Y471182I-1418J3202D01*
G02X801236Y471482I-1J3502D01*
G03X801074I-81J-183D01*
G02X799655Y471182I-1418J3202D01*
G02X798236Y471482I-1J3502D01*
G03X798074I-81J-183D01*
G02X796655Y471182I-1418J3202D01*
G02X793152Y474684I-1J3502D01*
G02X793453Y476103I3503J-2D01*
G03Y476265I-183J81D01*
G02X793152Y477684I3202J1421D01*
G02X793416Y479017I3503J-1D01*
G03Y479170I-185J77D01*
G02X793152Y480503I3239J1334D01*
G02X793453Y481922I3503J-2D01*
G03Y482084I-183J81D01*
G02X793152Y483503I3202J1421D01*
G02X793444Y484903I3502J0D01*
G03X793447Y485056I-183J80D01*
G02X793206Y486332I3262J1277D01*
G02X796709Y489834I3503J-1D01*
G02X798128Y489534I1J-3502D01*
G03X798290I81J183D01*
G02X799709Y489834I1418J-3202D01*
G02X801128Y489534I1J-3502D01*
G03X801290I81J183D01*
G02X802709Y489834I1418J-3202D01*
G02X804128Y489534I1J-3502D01*
G03X804290I81J183D01*
G02X805709Y489834I1418J-3202D01*
G02X807128Y489534I1J-3502D01*
G03X807290I81J183D01*
G02X808709Y489834I1418J-3202D01*
G02X810128Y489534I1J-3502D01*
G03X810290I81J183D01*
G37*
G36*
G01X866892D02*
G02X868311Y489834I1418J-3202D01*
G02X869730Y489534I1J-3502D01*
G03X869892I81J183D01*
G02X871311Y489834I1418J-3202D01*
G02X872730Y489534I1J-3502D01*
G03X872892I81J183D01*
G02X874311Y489834I1418J-3202D01*
G02X877814Y486332I1J-3502D01*
G02X877522Y484932I-3502J0D01*
G03X877519Y484779I183J-80D01*
G02X877760Y483503I-3262J-1277D01*
G02X877459Y482084I-3503J2D01*
G03Y481922I183J-81D01*
G02X877760Y480503I-3202J-1421D01*
G02X877496Y479170I-3503J1D01*
G03Y479017I185J-76D01*
G02X877760Y477684I-3239J-1334D01*
G02X877459Y476265I-3503J2D01*
G03Y476103I183J-81D01*
G02X877760Y474684I-3202J-1421D01*
G02X874257Y471182I-3503J1D01*
G02X872838Y471482I-1J3502D01*
G03X872676I-81J-183D01*
G02X871257Y471182I-1418J3202D01*
G02X869838Y471482I-1J3502D01*
G03X869676I-81J-183D01*
G02X868257Y471182I-1418J3202D01*
G02X866838Y471482I-1J3502D01*
G03X866676I-81J-183D01*
G02X865257Y471182I-1418J3202D01*
G02X863838Y471482I-1J3502D01*
G03X863676I-81J-183D01*
G02X862257Y471182I-1418J3202D01*
G02X860838Y471482I-1J3502D01*
G03X860676I-81J-183D01*
G02X859257Y471182I-1418J3202D01*
G02X857838Y471482I-1J3502D01*
G03X857676I-81J-183D01*
G02X856257Y471182I-1418J3202D01*
G02X854838Y471482I-1J3502D01*
G03X854676I-81J-183D01*
G02X853257Y471182I-1418J3202D01*
G02X849754Y474684I-1J3502D01*
G02X850055Y476103I3503J-2D01*
G03Y476265I-183J81D01*
G02X849754Y477684I3202J1421D01*
G02X850018Y479017I3503J-1D01*
G03Y479170I-185J77D01*
G02X849754Y480503I3239J1334D01*
G02X850055Y481922I3503J-2D01*
G03Y482084I-183J81D01*
G02X849754Y483503I3202J1421D01*
G02X850046Y484903I3502J0D01*
G03X850049Y485056I-183J80D01*
G02X849808Y486332I3262J1277D01*
G02X853311Y489834I3503J-1D01*
G02X854730Y489534I1J-3502D01*
G03X854892I81J183D01*
G02X856311Y489834I1418J-3202D01*
G02X857730Y489534I1J-3502D01*
G03X857892I81J183D01*
G02X859311Y489834I1418J-3202D01*
G02X860730Y489534I1J-3502D01*
G03X860892I81J183D01*
G02X862311Y489834I1418J-3202D01*
G02X863730Y489534I1J-3502D01*
G03X863892I81J183D01*
G02X865311Y489834I1418J-3202D01*
G02X866730Y489534I1J-3502D01*
G03X866892I81J183D01*
G37*
G36*
G01X68400Y475573D02*
X67972Y475638D01*
X67879Y475606D01*
X67844Y475568D01*
G02Y488842I-7214J6637D01*
G01X67879Y488804D01*
X67972Y488772D01*
X68400Y488837D01*
X68479Y488896D01*
X68500Y488942D01*
G02X82795Y498008I14295J-6737D01*
G02Y466402I0J-15803D01*
G02X68500Y475468I0J15803D01*
G01X68479Y475514D01*
X68400Y475573D01*
G37*
G36*
G01X1064581Y498702D02*
G02X1066000Y499002I1418J-3202D01*
G02X1067419Y498702I1J-3502D01*
G03X1067581I81J183D01*
G02X1069000Y499002I1418J-3202D01*
G02X1070419Y498702I1J-3502D01*
G03X1070581I81J183D01*
G02X1072000Y499002I1418J-3202D01*
G02X1075502Y495500I0J-3502D01*
G02X1075202Y494081I-3502J-1D01*
G03Y493919I183J-81D01*
G02X1075502Y492500I-3202J-1418D01*
G02X1072000Y488998I-3502J0D01*
G02X1070581Y489298I-1J3502D01*
G03X1070419I-81J-183D01*
G02X1069611Y489051I-1420J3202D01*
G03X1069449Y488889I35J-197D01*
G02X1069202Y488081I-3449J612D01*
G03Y487919I183J-81D01*
G02X1069449Y487111I-3202J-1420D01*
G03X1069611Y486949I197J35D01*
G02X1070419Y486702I-612J-3449D01*
G03X1070581I81J183D01*
G02X1072000Y487002I1418J-3202D01*
G02X1075502Y483500I0J-3502D01*
G02X1075202Y482081I-3502J-1D01*
G03Y481919I183J-81D01*
G02X1075502Y480500I-3202J-1418D01*
G02X1072000Y476998I-3502J0D01*
G02X1070581Y477298I-1J3502D01*
G03X1070419I-81J-183D01*
G02X1069000Y476998I-1418J3202D01*
G02X1067581Y477298I-1J3502D01*
G03X1067419I-81J-183D01*
G02X1066000Y476998I-1418J3202D01*
G02X1064581Y477298I-1J3502D01*
G03X1064419I-81J-183D01*
G02X1063000Y476998I-1418J3202D01*
G02X1061581Y477298I-1J3502D01*
G03X1061419I-81J-183D01*
G02X1060000Y476998I-1418J3202D01*
G02X1056498Y480500I0J3502D01*
G02X1056798Y481919I3502J1D01*
G03Y482081I-183J81D01*
G02X1056498Y483500I3202J1418D01*
G02X1056798Y484919I3502J1D01*
G03Y485081I-183J81D01*
G02X1056498Y486500I3202J1418D01*
G02X1056798Y487919I3502J1D01*
G03Y488081I-183J81D01*
G02X1056498Y489500I3202J1418D01*
G02X1056798Y490919I3502J1D01*
G03Y491081I-183J81D01*
G02X1056498Y492500I3202J1418D01*
G02X1056798Y493919I3502J1D01*
G03Y494081I-183J81D01*
G02X1056498Y495500I3202J1418D01*
G02X1060000Y499002I3502J0D01*
G02X1061419Y498702I1J-3502D01*
G03X1061581I81J183D01*
G02X1063000Y499002I1418J-3202D01*
G02X1064419Y498702I1J-3502D01*
G03X1064581I81J183D01*
G37*
G36*
G01X170520Y501202D02*
G02X171939Y501502I1418J-3202D01*
G02Y494498I0J-3502D01*
G02X170520Y494798I-1J3502D01*
G03X170358I-81J-183D01*
G02X168939Y494498I-1418J3202D01*
G02Y501502I0J3502D01*
G02X170358Y501202I1J-3502D01*
G03X170520I81J183D01*
G37*
G36*
G01X218520D02*
G02X219939Y501502I1418J-3202D01*
G02Y494498I0J-3502D01*
G02X218520Y494798I-1J3502D01*
G03X218358I-81J-183D01*
G02X216939Y494498I-1418J3202D01*
G02Y501502I0J3502D01*
G02X218358Y501202I1J-3502D01*
G03X218520I81J183D01*
G37*
G36*
G01X266520D02*
G02X267939Y501502I1418J-3202D01*
G02Y494498I0J-3502D01*
G02X266520Y494798I-1J3502D01*
G03X266358I-81J-183D01*
G02X264939Y494498I-1418J3202D01*
G02Y501502I0J3502D01*
G02X266358Y501202I1J-3502D01*
G03X266520I81J183D01*
G37*
G36*
G01X328000D02*
G02X329419Y501502I1418J-3202D01*
G02Y494498I0J-3502D01*
G02X328000Y494798I-1J3502D01*
G03X327838I-81J-183D01*
G02X326419Y494498I-1418J3202D01*
G02Y501502I0J3502D01*
G02X327838Y501202I1J-3502D01*
G03X328000I81J183D01*
G37*
G36*
G01X376000D02*
G02X377419Y501502I1418J-3202D01*
G02Y494498I0J-3502D01*
G02X376000Y494798I-1J3502D01*
G03X375838I-81J-183D01*
G02X374419Y494498I-1418J3202D01*
G02Y501502I0J3502D01*
G02X375838Y501202I1J-3502D01*
G03X376000I81J183D01*
G37*
G36*
G01X424000D02*
G02X425419Y501502I1418J-3202D01*
G02Y494498I0J-3502D01*
G02X424000Y494798I-1J3502D01*
G03X423838I-81J-183D01*
G02X422419Y494498I-1418J3202D01*
G02Y501502I0J3502D01*
G02X423838Y501202I1J-3502D01*
G03X424000I81J183D01*
G37*
G36*
G01X485481D02*
G02X486900Y501502I1418J-3202D01*
G02Y494498I0J-3502D01*
G02X485481Y494798I-1J3502D01*
G03X485319I-81J-183D01*
G02X483900Y494498I-1418J3202D01*
G02Y501502I0J3502D01*
G02X485319Y501202I1J-3502D01*
G03X485481I81J183D01*
G37*
G36*
G01X533481D02*
G02X534900Y501502I1418J-3202D01*
G02Y494498I0J-3502D01*
G02X533481Y494798I-1J3502D01*
G03X533319I-81J-183D01*
G02X531900Y494498I-1418J3202D01*
G02Y501502I0J3502D01*
G02X533319Y501202I1J-3502D01*
G03X533481I81J183D01*
G37*
G36*
G01X581481D02*
G02X582900Y501502I1418J-3202D01*
G02Y494498I0J-3502D01*
G02X581481Y494798I-1J3502D01*
G03X581319I-81J-183D01*
G02X579900Y494498I-1418J3202D01*
G02Y501502I0J3502D01*
G02X581319Y501202I1J-3502D01*
G03X581481I81J183D01*
G37*
G36*
G01X642962D02*
G02X644381Y501502I1418J-3202D01*
G02Y494498I0J-3502D01*
G02X642962Y494798I-1J3502D01*
G03X642800I-81J-183D01*
G02X641381Y494498I-1418J3202D01*
G02Y501502I0J3502D01*
G02X642800Y501202I1J-3502D01*
G03X642962I81J183D01*
G37*
G36*
G01X690962D02*
G02X692381Y501502I1418J-3202D01*
G02Y494498I0J-3502D01*
G02X690962Y494798I-1J3502D01*
G03X690800I-81J-183D01*
G02X689381Y494498I-1418J3202D01*
G02Y501502I0J3502D01*
G02X690800Y501202I1J-3502D01*
G03X690962I81J183D01*
G37*
G36*
G01X738962D02*
G02X740381Y501502I1418J-3202D01*
G02Y494498I0J-3502D01*
G02X738962Y494798I-1J3502D01*
G03X738800I-81J-183D01*
G02X737381Y494498I-1418J3202D01*
G02Y501502I0J3502D01*
G02X738800Y501202I1J-3502D01*
G03X738962I81J183D01*
G37*
G36*
G01X170520Y521202D02*
G02X171939Y521502I1418J-3202D01*
G02Y514498I0J-3502D01*
G02X170520Y514798I-1J3502D01*
G03X170358I-81J-183D01*
G02X168939Y514498I-1418J3202D01*
G02Y521502I0J3502D01*
G02X170358Y521202I1J-3502D01*
G03X170520I81J183D01*
G37*
G36*
G01X218520D02*
G02X219939Y521502I1418J-3202D01*
G02Y514498I0J-3502D01*
G02X218520Y514798I-1J3502D01*
G03X218358I-81J-183D01*
G02X216939Y514498I-1418J3202D01*
G02Y521502I0J3502D01*
G02X218358Y521202I1J-3502D01*
G03X218520I81J183D01*
G37*
G36*
G01X266520D02*
G02X267939Y521502I1418J-3202D01*
G02Y514498I0J-3502D01*
G02X266520Y514798I-1J3502D01*
G03X266358I-81J-183D01*
G02X264939Y514498I-1418J3202D01*
G02Y521502I0J3502D01*
G02X266358Y521202I1J-3502D01*
G03X266520I81J183D01*
G37*
G36*
G01X328000D02*
G02X329419Y521502I1418J-3202D01*
G02Y514498I0J-3502D01*
G02X328000Y514798I-1J3502D01*
G03X327838I-81J-183D01*
G02X326419Y514498I-1418J3202D01*
G02Y521502I0J3502D01*
G02X327838Y521202I1J-3502D01*
G03X328000I81J183D01*
G37*
G36*
G01X376000D02*
G02X377419Y521502I1418J-3202D01*
G02Y514498I0J-3502D01*
G02X376000Y514798I-1J3502D01*
G03X375838I-81J-183D01*
G02X374419Y514498I-1418J3202D01*
G02Y521502I0J3502D01*
G02X375838Y521202I1J-3502D01*
G03X376000I81J183D01*
G37*
G36*
G01X424000D02*
G02X425419Y521502I1418J-3202D01*
G02Y514498I0J-3502D01*
G02X424000Y514798I-1J3502D01*
G03X423838I-81J-183D01*
G02X422419Y514498I-1418J3202D01*
G02Y521502I0J3502D01*
G02X423838Y521202I1J-3502D01*
G03X424000I81J183D01*
G37*
G36*
G01X485481D02*
G02X486900Y521502I1418J-3202D01*
G02Y514498I0J-3502D01*
G02X485481Y514798I-1J3502D01*
G03X485319I-81J-183D01*
G02X483900Y514498I-1418J3202D01*
G02Y521502I0J3502D01*
G02X485319Y521202I1J-3502D01*
G03X485481I81J183D01*
G37*
G36*
G01X533481D02*
G02X534900Y521502I1418J-3202D01*
G02Y514498I0J-3502D01*
G02X533481Y514798I-1J3502D01*
G03X533319I-81J-183D01*
G02X531900Y514498I-1418J3202D01*
G02Y521502I0J3502D01*
G02X533319Y521202I1J-3502D01*
G03X533481I81J183D01*
G37*
G36*
G01X581481D02*
G02X582900Y521502I1418J-3202D01*
G02Y514498I0J-3502D01*
G02X581481Y514798I-1J3502D01*
G03X581319I-81J-183D01*
G02X579900Y514498I-1418J3202D01*
G02Y521502I0J3502D01*
G02X581319Y521202I1J-3502D01*
G03X581481I81J183D01*
G37*
G36*
G01X642962D02*
G02X644381Y521502I1418J-3202D01*
G02Y514498I0J-3502D01*
G02X642962Y514798I-1J3502D01*
G03X642800I-81J-183D01*
G02X641381Y514498I-1418J3202D01*
G02Y521502I0J3502D01*
G02X642800Y521202I1J-3502D01*
G03X642962I81J183D01*
G37*
G36*
G01X690962D02*
G02X692381Y521502I1418J-3202D01*
G02Y514498I0J-3502D01*
G02X690962Y514798I-1J3502D01*
G03X690800I-81J-183D01*
G02X689381Y514498I-1418J3202D01*
G02Y521502I0J3502D01*
G02X690800Y521202I1J-3502D01*
G03X690962I81J183D01*
G37*
G36*
G01X738962D02*
G02X740381Y521502I1418J-3202D01*
G02Y514498I0J-3502D01*
G02X738962Y514798I-1J3502D01*
G03X738800I-81J-183D01*
G02X737381Y514498I-1418J3202D01*
G02Y521502I0J3502D01*
G02X738800Y521202I1J-3502D01*
G03X738962I81J183D01*
G37*
G36*
G01X916288Y522263D02*
G02X917596Y522516I1307J-3249D01*
G02X919015Y522216I1J-3502D01*
G03X919177I81J183D01*
G02X920596Y522516I1418J-3202D01*
G02X922015Y522216I1J-3502D01*
G03X922177I81J183D01*
G02X923596Y522516I1418J-3202D01*
G02X927098Y519014I0J-3502D01*
G02X926806Y517614I-3502J0D01*
G03X926803Y517461I184J-80D01*
G02X927044Y516184I-3261J-1277D01*
G02X926744Y514765I-3502J-1D01*
G03Y514603I183J-81D01*
G02X927044Y513184I-3202J-1418D01*
G02X926744Y511765I-3502J-1D01*
G03Y511603I183J-81D01*
G02X927044Y510184I-3202J-1418D01*
G02X926744Y508765I-3502J-1D01*
G03Y508603I183J-81D01*
G02X927044Y507184I-3202J-1418D01*
G02X926744Y505765I-3502J-1D01*
G03Y505603I183J-81D01*
G02X927044Y504184I-3202J-1418D01*
G02X926744Y502765I-3502J-1D01*
G03Y502603I183J-81D01*
G02X927044Y501184I-3202J-1418D01*
G02X926823Y499959I-3502J-1D01*
G03X926826Y499812I188J-70D01*
G02X927098Y498461I-3231J-1353D01*
G02X923595Y494958I-3503J0D01*
G02X922176Y495259I2J3503D01*
G03X922014I-81J-183D01*
G02X920595Y494958I-1421J3202D01*
G02X919176Y495259I2J3503D01*
G03X919014I-81J-183D01*
G02X917595Y494958I-1421J3202D01*
G02X916287Y495212I2J3503D01*
G03X916137I-75J-186D01*
G02X914829Y494958I-1310J3249D01*
G02X913410Y495259I2J3503D01*
G03X913248I-81J-183D01*
G02X911829Y494958I-1421J3202D01*
G02X908326Y498461I0J3503D01*
G02X908548Y499686I3503J-2D01*
G03X908545Y499833I-188J70D01*
G02X908274Y501184I3232J1351D01*
G02X908574Y502603I3502J1D01*
G03Y502765I-183J81D01*
G02X908274Y504184I3202J1418D01*
G02X908574Y505603I3502J1D01*
G03Y505765I-183J81D01*
G02X908274Y507184I3202J1418D01*
G02X908574Y508603I3502J1D01*
G03Y508765I-183J81D01*
G02X908274Y510184I3202J1418D01*
G02X908574Y511603I3502J1D01*
G03Y511765I-183J81D01*
G02X908274Y513184I3202J1418D01*
G02X908574Y514603I3502J1D01*
G03Y514765I-183J81D01*
G02X908274Y516184I3202J1418D01*
G02X908566Y517584I3502J0D01*
G03X908569Y517737I-184J80D01*
G02X908328Y519014I3261J1277D01*
G02X911830Y522516I3502J0D01*
G02X913249Y522216I1J-3502D01*
G03X913411I81J183D01*
G02X914830Y522516I1418J-3202D01*
G02X916138Y522263I1J-3502D01*
G03X916288I75J186D01*
G37*
G36*
G01X1093861Y519502D02*
X1099239Y524880D01*
G02X1100653Y525466I1414J-1413D01*
G01X1175329D01*
G02X1176743Y524880I0J-1999D01*
G01X1181585Y520038D01*
G02X1182171Y518624I-1413J-1414D01*
G01Y497840D01*
G03X1182230Y497698I200J0D01*
G01X1196769Y483159D01*
G03X1196911Y483100I142J141D01*
G01X1258400D01*
G02X1259814Y482514I0J-1999D01*
G01X1264914Y477414D01*
G02X1265500Y476000I-1413J-1414D01*
G01Y302600D01*
G02X1264914Y301186I-1999J0D01*
G01X1260814Y297086D01*
G02X1259400Y296500I-1414J1413D01*
G01X1216111D01*
G03X1215969Y296441I0J-200D01*
G01X1208559Y289031D01*
G03X1208500Y288889I141J-142D01*
G01Y222800D01*
G02X1207914Y221386I-1999J0D01*
G01X1177914Y191386D01*
G02X1176500Y190800I-1414J1413D01*
G01X1170652D01*
G03X1170452Y190600I0J-200D01*
G01Y187837D01*
G02X1170253Y187438I-500J0D01*
G01X1170219Y187412D01*
X1170178Y187339D01*
X1170142Y186961D01*
X1170169Y186881D01*
X1170197Y186850D01*
G02X1171102Y184500I-2597J-2349D01*
G02X1170548Y182608I-3502J-2D01*
G03Y182392I168J-108D01*
G02X1171102Y180500I-2948J-1890D01*
G02X1167600Y176998I-3502J0D01*
G02X1166632Y177134I-2J3502D01*
G01X1166581Y177148D01*
X1166480Y177124D01*
X1166151Y176820D01*
X1166119Y176720D01*
X1166130Y176668D01*
G02X1166202Y175959I-3430J-707D01*
G02X1162700Y172456I-3502J-1D01*
G02X1161487Y172673I1J3503D01*
G03X1161352Y172674I-69J-188D01*
G02X1160200Y172480I-1149J3308D01*
G02X1156715Y175628I0J3503D01*
G03X1156597Y175791I-199J-20D01*
G02X1154498Y179000I1403J3209D01*
G02X1158000Y182502I3502J0D01*
G02X1161435Y179684I0J-3503D01*
G01X1161443Y179645D01*
X1161488Y179578D01*
X1161797Y179378D01*
X1161877Y179364D01*
X1161917Y179373D01*
G02X1162700Y179462I785J-3414D01*
G02X1163668Y179325I-2J-3503D01*
G01X1163719Y179311D01*
X1163820Y179335D01*
X1164149Y179639D01*
X1164181Y179739D01*
X1164170Y179791D01*
G02X1164098Y180500I3430J707D01*
G02X1164652Y182392I3502J2D01*
G03Y182608I-168J108D01*
G02X1164098Y184500I2948J1890D01*
G02X1164976Y186820I3502J1D01*
G01X1165005Y186853D01*
X1165030Y186935D01*
X1164979Y187322D01*
X1164933Y187395D01*
X1164896Y187419D01*
G02X1164671Y187837I276J418D01*
G01Y190600D01*
G03X1164471Y190800I-200J0D01*
G01X1109109D01*
G03X1109009Y190773I0J-200D01*
G02X1108001Y190500I-1009J1727D01*
G01X1108000D01*
G02X1106586Y191086I0J1999D01*
G01X1093861Y203811D01*
G02X1093275Y205225I1413J1414D01*
G01Y518088D01*
G02X1093861Y519502I1999J0D01*
G37*
G36*
G01X839232Y519045D02*
G02X838932Y520464I3202J1418D01*
G02X839232Y521883I3502J1D01*
G03Y522045I-183J81D01*
G02X838932Y523464I3202J1418D01*
G02X842434Y526966I3502J0D01*
G02X843834Y526675I2J-3502D01*
G03X843987Y526672I80J183D01*
G02X845263Y526912I1274J-3262D01*
G02X846682Y526612I1J-3502D01*
G03X846844I81J183D01*
G02X848263Y526912I1418J-3202D01*
G02X849596Y526649I1J-3502D01*
G03X849749I77J185D01*
G02X851082Y526912I1332J-3239D01*
G02X852501Y526612I1J-3502D01*
G03X852663I81J183D01*
G02X854082Y526912I1418J-3202D01*
G02X857584Y523410I0J-3502D01*
G02X857284Y521991I-3502J-1D01*
G03Y521829I183J-81D01*
G02X857584Y520410I-3202J-1418D01*
G02X857284Y518991I-3502J-1D01*
G03Y518829I183J-81D01*
G02X857584Y517410I-3202J-1418D01*
G02X857284Y515991I-3502J-1D01*
G03Y515829I183J-81D01*
G02X857584Y514410I-3202J-1418D01*
G02X857284Y512991I-3502J-1D01*
G03Y512829I183J-81D01*
G02X857584Y511410I-3202J-1418D01*
G02X857284Y509991I-3502J-1D01*
G03Y509829I183J-81D01*
G02X857584Y508410I-3202J-1418D01*
G02X857284Y506991I-3502J-1D01*
G03Y506829I183J-81D01*
G02X857584Y505410I-3202J-1418D01*
G02X857284Y503991I-3502J-1D01*
G03Y503829I183J-81D01*
G02X857584Y502410I-3202J-1418D01*
G02X854082Y498908I-3502J0D01*
G02X852663Y499208I-1J3502D01*
G03X852501I-81J-183D01*
G02X851082Y498908I-1418J3202D01*
G02X849749Y499171I-1J3502D01*
G03X849596I-76J-185D01*
G02X848263Y498908I-1332J3239D01*
G02X846844Y499208I-1J3502D01*
G03X846682I-81J-183D01*
G02X845263Y498908I-1418J3202D01*
G02X843863Y499199I-2J3502D01*
G03X843710Y499202I-80J-183D01*
G02X842434Y498962I-1274J3262D01*
G02X838932Y502464I0J3502D01*
G02X839232Y503883I3502J1D01*
G03Y504045I-183J81D01*
G02X838932Y505464I3202J1418D01*
G02X839232Y506883I3502J1D01*
G03Y507045I-183J81D01*
G02X838932Y508464I3202J1418D01*
G02X839232Y509883I3502J1D01*
G03Y510045I-183J81D01*
G02X838932Y511464I3202J1418D01*
G02X839232Y512883I3502J1D01*
G03Y513045I-183J81D01*
G02X838932Y514464I3202J1418D01*
G02X839232Y515883I3502J1D01*
G03Y516045I-183J81D01*
G02X838932Y517464I3202J1418D01*
G02X839232Y518883I3502J1D01*
G03Y519045I-183J81D01*
G37*
G36*
G01X1063298Y548581D02*
G02X1062998Y550000I3202J1418D01*
G02X1063298Y551419I3502J1D01*
G03Y551581I-183J81D01*
G02X1062998Y553000I3202J1418D01*
G02X1066500Y556502I3502J0D01*
G02X1067919Y556202I1J-3502D01*
G03X1068081I81J183D01*
G02X1069500Y556502I1418J-3202D01*
G02X1073002Y553000I0J-3502D01*
G02X1072702Y551581I-3502J-1D01*
G03Y551419I183J-81D01*
G02X1073002Y550000I-3202J-1418D01*
G02X1072702Y548581I-3502J-1D01*
G03Y548419I183J-81D01*
G02X1073002Y547000I-3202J-1418D01*
G02X1072702Y545581I-3502J-1D01*
G03Y545419I183J-81D01*
G02X1073002Y544000I-3202J-1418D01*
G02X1072702Y542581I-3502J-1D01*
G03Y542419I183J-81D01*
G02X1073002Y541000I-3202J-1418D01*
G02X1072702Y539581I-3502J-1D01*
G03Y539419I183J-81D01*
G02X1073002Y538000I-3202J-1418D01*
G02X1069500Y534498I-3502J0D01*
G02X1068081Y534798I-1J3502D01*
G03X1067919I-81J-183D01*
G02X1066500Y534498I-1418J3202D01*
G02X1062998Y538000I0J3502D01*
G02X1063298Y539419I3502J1D01*
G03Y539581I-183J81D01*
G02X1062998Y541000I3202J1418D01*
G02X1063298Y542419I3502J1D01*
G03Y542581I-183J81D01*
G02X1062998Y544000I3202J1418D01*
G02X1063298Y545419I3502J1D01*
G03Y545581I-183J81D01*
G02X1062998Y547000I3202J1418D01*
G02X1063298Y548419I3502J1D01*
G03Y548581I-183J81D01*
G37*
G36*
G01X159774Y229052D02*
G02X159348Y230728I3076J1674D01*
G02X162850Y234230I3502J0D01*
G02X164032Y234025I1J-3502D01*
G03X164168I68J188D01*
G02X165350Y234230I1181J-3297D01*
G02X168852Y230728I0J-3502D01*
G02X168426Y229052I-3502J-2D01*
G03Y228861I175J-95D01*
G02X168852Y227185I-3076J-1674D01*
G02X168426Y225509I-3502J-2D01*
G03Y225318I175J-95D01*
G02X168852Y223642I-3076J-1674D01*
G02X168425Y221966I-3503J0D01*
G03Y221774I176J-96D01*
G02X168852Y220098I-3076J-1676D01*
G02X166105Y216678I-3502J0D01*
G03X166073Y216297I43J-195D01*
G02X166132Y216273I-1290J-3256D01*
G03X166288I78J184D01*
G02X167660Y216552I1370J-3223D01*
G02X171162Y213050I0J-3502D01*
G02X170819Y211536I-3503J-2D01*
G03Y211364I180J-86D01*
G02X171162Y209850I-3160J-1512D01*
G02X167660Y206348I-3502J0D01*
G02X166288Y206627I-2J3502D01*
G03X166132I-78J-184D01*
G02X164760Y206348I-1370J3223D01*
G02X161258Y209850I0J3502D01*
G02X161601Y211364I3503J2D01*
G03Y211536I-180J86D01*
G02X161258Y213050I3160J1512D01*
G02X162709Y215889I3503J0D01*
G01X162761Y215926D01*
X162802Y216043D01*
X162671Y216526D01*
X162576Y216606D01*
X162513Y216612D01*
G02X159348Y220098I337J3486D01*
G02X159775Y221774I3503J0D01*
G03Y221966I-176J96D01*
G02X159348Y223642I3076J1676D01*
G02X159774Y225318I3502J2D01*
G03Y225509I-175J96D01*
G02X159348Y227185I3076J1674D01*
G02X159774Y228861I3502J2D01*
G03Y229052I-175J95D01*
G37*
G54D56*
X247441Y305975D03*
X404921D03*
X562402D03*
X719883D03*
X849000Y399000D03*
X1016614Y197767D03*
X1024340Y146600D03*
X1084325Y130197D03*
X1092000Y82500D03*
X154840Y244730D03*
X1067866Y507629D03*
X1060984Y418742D03*
X1061600Y513742D03*
Y466242D03*
X1086500Y403500D03*
X1061600Y323742D03*
X1086500Y356000D03*
X1158200Y137700D03*
X1067531Y412942D03*
X1067679Y317942D03*
X1067707Y365442D03*
X1067701Y270442D03*
X1061600Y276242D03*
X1152781Y165719D03*
X1152500Y186500D03*
X1080418Y373600D03*
X1067730Y460352D03*
G54D59*
X1226024Y286929D03*
G54D57*
X268000Y240000D03*
X312500D03*
X357000D03*
X428500D03*
X472500D03*
X516500D03*
X578500D03*
X622500D03*
X666500D03*
X735981D03*
X779981D03*
X823981D03*
G54D55*
X165539Y539000D03*
X213539D03*
X261539D03*
X323019D03*
X371019D03*
X419019D03*
X480500D03*
X528500D03*
X576500D03*
X637981D03*
X685981D03*
X733981D03*
G54D58*
X253819Y477204D03*
X411299D03*
X568780D03*
X726261D03*
G54D52*
X19922Y367716D03*
Y214173D03*
G54D53*
X964460Y16950D03*
X877510Y558620D03*
X175000Y100500D03*
X1271654Y636929D03*
X619685D03*
G54D54*
X108858Y99724D03*
Y482205D03*
G54D51*
X665059Y149408D03*
X980059D03*
X529252Y129685D03*
X249252D03*
X1226024Y174429D03*
%LPC*%
G75*
G36*
G01X1102061Y377400D02*
X1173385D01*
G02X1173527Y377341I0J-200D01*
G01X1178112Y372756D01*
G02X1178171Y372614I-141J-142D01*
G01Y338657D01*
G02X1178140Y338551I-200J1D01*
G03X1177909Y337750I1271J-800D01*
G03X1178140Y336949I1502J-1D01*
G02X1178171Y336843I-169J-107D01*
G01Y335157D01*
G02X1178140Y335051I-200J1D01*
G03X1177909Y334250I1271J-800D01*
G03X1178140Y333449I1502J-1D01*
G02X1178171Y333343I-169J-107D01*
G01Y331657D01*
G02X1178140Y331551I-200J1D01*
G03X1177909Y330750I1271J-800D01*
G03X1178140Y329949I1502J-1D01*
G02X1178171Y329843I-169J-107D01*
G01Y328157D01*
G02X1178140Y328051I-200J1D01*
G03X1177909Y327250I1271J-800D01*
G03X1178140Y326449I1502J-1D01*
G02X1178171Y326343I-169J-107D01*
G01Y310199D01*
X1178168Y310183D01*
G03X1178149Y309942I1483J-238D01*
G03X1178168Y309701I1502J-3D01*
G01X1178171Y309685D01*
Y306199D01*
X1178168Y306183D01*
G03X1178149Y305942I1483J-238D01*
G03X1178168Y305701I1502J-3D01*
G01X1178171Y305685D01*
Y240893D01*
G02X1178112Y240751I-200J0D01*
G01X1174527Y237166D01*
G02X1174385Y237107I-142J141D01*
G01X1101890D01*
G02X1101748Y237166I0J200D01*
G01X1097334Y241580D01*
G02X1097275Y241722I141J142D01*
G01Y372614D01*
G02X1097334Y372756I200J0D01*
G01X1101919Y377341D01*
G02X1102061Y377400I142J-141D01*
G37*
G36*
G01X1101564Y521466D02*
X1174418D01*
G02X1174560Y521407I0J-200D01*
G01X1178112Y517855D01*
G02X1178171Y517713I-141J-142D01*
G01Y480974D01*
X1178161Y480931D01*
X1178151Y480910D01*
G03X1177998Y480250I1349J-660D01*
G03X1178151Y479590I1502J0D01*
G01X1178161Y479569D01*
X1178171Y479526D01*
Y477474D01*
X1178161Y477431D01*
X1178151Y477410D01*
G03X1177998Y476750I1349J-660D01*
G03X1178151Y476090I1502J0D01*
G01X1178161Y476069D01*
X1178171Y476026D01*
Y473974D01*
X1178161Y473931D01*
X1178151Y473910D01*
G03X1177998Y473250I1349J-660D01*
G03X1178151Y472590I1502J0D01*
G01X1178161Y472569D01*
X1178171Y472526D01*
Y470474D01*
X1178161Y470431D01*
X1178151Y470410D01*
G03X1177998Y469750I1349J-660D01*
G03X1178151Y469090I1502J0D01*
G01X1178161Y469069D01*
X1178171Y469026D01*
Y386186D01*
G02X1178112Y386044I-200J0D01*
G01X1173527Y381459D01*
G02X1173385Y381400I-142J141D01*
G01X1102061D01*
G02X1101919Y381459I0J200D01*
G01X1097334Y386044D01*
G02X1097275Y386186I141J142D01*
G01Y517177D01*
G02X1097334Y517319I200J0D01*
G01X1101422Y521407D01*
G02X1101564Y521466I142J-141D01*
G37*
G36*
G01X1205314Y291525D02*
X1184505D01*
G02X1184363Y291584I0J200D01*
G01X1182230Y293717D01*
G02X1182171Y293859I141J142D01*
G01Y348245D01*
G02X1182208Y348361I200J0D01*
G03Y350107I-1222J873D01*
G02X1182171Y350223I163J116D01*
G01Y474987D01*
G02X1182230Y475129I200J0D01*
G01X1186142Y479041D01*
G02X1186284Y479100I142J-141D01*
G01X1257489D01*
G02X1257631Y479041I0J-200D01*
G01X1261441Y475231D01*
G02X1261500Y475089I-141J-142D01*
G01Y303511D01*
G02X1261441Y303369I-200J0D01*
G01X1258631Y300559D01*
G02X1258489Y300500I-142J141D01*
G01X1215200D01*
G03X1213786Y299914I0J-1999D01*
G01X1205456Y291584D01*
G02X1205314Y291525I-142J141D01*
G37*
%LPD*%
G75*
G54D60*
X1226024Y399429D03*
G54D20*
X63436Y353962D03*
X108600Y258560D03*
X111600D03*
X108600Y261560D03*
X111600D03*
X108600Y255560D03*
X111600D03*
X123000Y414500D03*
X119500D03*
Y411500D03*
X123000D03*
X119500Y408500D03*
X123000D03*
X119500Y417500D03*
X123000D03*
X119500Y420500D03*
X123000D03*
X115700Y420600D03*
Y417600D03*
Y408600D03*
Y411600D03*
Y414600D03*
X123000Y426600D03*
X119500D03*
X123000Y423600D03*
X119500D03*
X115700Y423700D03*
Y426700D03*
X150634Y219063D03*
X154840Y244730D03*
X155034Y228063D03*
Y224563D03*
X152334Y223063D03*
Y226563D03*
Y230063D03*
X155034Y231563D03*
X182260Y197050D03*
X179460D03*
X176560D03*
X174660Y205850D03*
Y202650D03*
X167660Y213050D03*
X164760D03*
X167660Y209850D03*
X164760D03*
X183900Y216830D03*
X178265Y213443D03*
X175976Y218775D03*
X165840Y247805D03*
X169840D03*
X166068Y238749D03*
X173869Y228168D03*
X175481Y225183D03*
X160017Y237764D03*
X161400Y323200D03*
X157000Y414500D03*
X160500D03*
Y417500D03*
X157000D03*
X160500Y420500D03*
X157000D03*
X160500Y411500D03*
X157000D03*
X160500Y408500D03*
X157000D03*
X164000Y414600D03*
Y417600D03*
Y420600D03*
Y411600D03*
Y408600D03*
X160300Y423600D03*
X156800D03*
X160300Y426600D03*
X156800D03*
X163800Y426700D03*
Y423700D03*
X168939Y498000D03*
X171939D03*
Y518000D03*
X168939D03*
X194160Y205200D03*
Y208200D03*
X200160Y205200D03*
Y208200D03*
X197160Y205200D03*
Y208200D03*
X185260Y205350D03*
Y208350D03*
X203575Y297500D03*
X212925Y315500D03*
X218500Y309500D03*
X226975D03*
X235975D03*
X230425Y313605D03*
X221425Y313000D03*
X216939Y498000D03*
X219939D03*
Y518000D03*
X216939D03*
X247441Y305975D03*
X264939Y498000D03*
X267939D03*
Y518000D03*
X264939D03*
X283000Y203500D03*
Y198500D03*
Y196000D03*
Y206000D03*
X285219Y279078D03*
X281219D03*
X277219D03*
X285219Y275078D03*
X281219D03*
X277219D03*
X285219Y271078D03*
X281219D03*
X277219D03*
Y283078D03*
X281219D03*
X285219D03*
X326000Y203500D03*
Y198500D03*
Y196000D03*
Y206000D03*
X304500Y203500D03*
Y198500D03*
Y196000D03*
Y206000D03*
X326419Y498000D03*
X329419D03*
Y518000D03*
X326419D03*
X347500Y203500D03*
Y198500D03*
Y196000D03*
Y206000D03*
X361000Y305975D03*
X390500Y203500D03*
Y198500D03*
Y196000D03*
Y206000D03*
X369000Y203500D03*
Y198500D03*
Y196000D03*
Y206000D03*
X375500Y309500D03*
X383975D03*
X382963Y316400D03*
Y313750D03*
X374419Y498000D03*
X377419D03*
Y518000D03*
X374419D03*
X412000Y203500D03*
Y198500D03*
Y196000D03*
Y206000D03*
X404921Y305975D03*
X392975Y309500D03*
X442499Y279186D03*
X438499D03*
X434499D03*
X442499Y275186D03*
X438499D03*
X434499D03*
X442499Y271186D03*
X438499D03*
X434499D03*
Y283186D03*
X438499D03*
X442499D03*
X422419Y498000D03*
X425419D03*
Y518000D03*
X422419D03*
X483900Y498000D03*
X486900D03*
Y518000D03*
X483900D03*
X518575Y295500D03*
X533475Y310500D03*
X539619Y316400D03*
Y313400D03*
X531900Y498000D03*
X534900D03*
Y518000D03*
X531900D03*
X562402Y305975D03*
X542475Y310500D03*
X551475D03*
X562000Y442000D03*
X564500D03*
X590500Y203000D03*
Y198000D03*
Y195500D03*
Y205500D03*
X582900Y518000D03*
Y498000D03*
X579900D03*
Y518000D03*
X612000Y203000D03*
Y198000D03*
Y195500D03*
Y205500D03*
X640900Y42300D03*
X647999Y33000D03*
X638200Y44000D03*
Y46500D03*
X641100Y48100D03*
X655000Y203000D03*
Y198000D03*
Y195500D03*
Y205500D03*
X633500Y203000D03*
Y198000D03*
Y195500D03*
Y205500D03*
X644381Y518000D03*
Y498000D03*
X641381D03*
Y518000D03*
X690075Y39500D03*
X676500Y195500D03*
Y198000D03*
Y203000D03*
Y205500D03*
X676075Y299600D03*
X680400Y310500D03*
X703740Y41000D03*
X707000Y32000D03*
X694425Y29500D03*
X703740Y54118D03*
X697990Y195500D03*
Y198000D03*
Y203000D03*
Y205500D03*
X716100Y255987D03*
X700040Y258960D03*
X694406Y295500D03*
X690956Y310500D03*
X699956D03*
X708956D03*
X697100Y313400D03*
X704400Y358600D03*
X702200Y356000D03*
X697900Y352500D03*
X707750Y358750D03*
X692381Y518000D03*
Y498000D03*
X689381D03*
Y518000D03*
X747160Y30000D03*
Y38500D03*
Y64000D03*
Y47000D03*
Y55500D03*
X719490Y195500D03*
Y198000D03*
Y203000D03*
Y205500D03*
X719883Y305975D03*
X724000Y294500D03*
X742500Y328500D03*
Y324500D03*
Y334500D03*
X735075Y326000D03*
Y336000D03*
X731925D03*
X732000Y326000D03*
X742000Y341500D03*
X742500Y347700D03*
Y353200D03*
X740381Y518000D03*
Y498000D03*
X737381D03*
Y518000D03*
X750300Y27200D03*
X752560Y30100D03*
X749760D03*
X752560Y38600D03*
X749760D03*
X752560Y64100D03*
X749760D03*
X752560Y47100D03*
X749760D03*
X752560Y55600D03*
X749760D03*
X754000Y353500D03*
Y356957D03*
X748075Y366500D03*
X803900Y279425D03*
X803500Y259525D03*
X784855Y265184D03*
X790000Y259612D03*
X794900Y265979D03*
X806000Y265075D03*
X806500Y285500D03*
X800575Y338000D03*
X779100Y326820D03*
X798400Y323900D03*
X786500Y316700D03*
X793800Y323880D03*
X781500Y362700D03*
X803000Y357000D03*
Y346500D03*
X802975Y362000D03*
X792000Y358000D03*
X805323Y408150D03*
Y405150D03*
X799323D03*
Y408150D03*
X802323Y405150D03*
Y408150D03*
X796600Y408097D03*
Y405097D03*
X802323Y416916D03*
X799323D03*
X805323D03*
X802323Y413916D03*
X799323D03*
X805323D03*
Y411150D03*
X799323D03*
X802323D03*
X796600Y411097D03*
Y413863D03*
Y416863D03*
X799655Y474684D03*
Y480503D03*
Y477684D03*
X802655Y474684D03*
Y480503D03*
Y477684D03*
X805655Y474684D03*
Y480503D03*
Y477684D03*
X802655Y483503D03*
X805709Y486332D03*
X805655Y483503D03*
X796655Y474684D03*
Y480503D03*
Y477684D03*
X796709Y486332D03*
X796655Y483503D03*
X799709Y486332D03*
X799655Y483503D03*
X802709Y486332D03*
X831000Y270500D03*
X808500Y276075D03*
X836000Y270500D03*
X826000Y270525D03*
X833500Y268575D03*
X821000Y270525D03*
X816000D03*
X827602Y283500D03*
X836500Y302500D03*
X814500Y293000D03*
X811500Y329000D03*
X815500D03*
X823500D03*
X819500Y318500D03*
X808425Y334000D03*
X831750Y318250D03*
X829500Y354925D03*
X827000Y360475D03*
X811575Y344000D03*
X827000Y352500D03*
X808425Y344000D03*
X811323Y405150D03*
Y408150D03*
X808323D03*
Y405150D03*
Y416916D03*
X811323D03*
X808323Y413916D03*
X811323D03*
Y411150D03*
X808323D03*
X817153Y408096D03*
Y405096D03*
X814323Y405150D03*
Y408150D03*
Y416916D03*
X817153Y416862D03*
X814323Y413916D03*
X817153Y413862D03*
Y411096D03*
X814323Y411150D03*
X817709Y486332D03*
X817655Y483503D03*
X808655Y474684D03*
Y480503D03*
Y477684D03*
X811655Y474684D03*
Y480503D03*
Y477684D03*
X814655D03*
Y480503D03*
Y474684D03*
X808709Y486332D03*
X808655Y483503D03*
X811709Y486332D03*
X811655Y483503D03*
X814655D03*
X814709Y486332D03*
X817655Y474684D03*
Y480503D03*
Y477684D03*
X863600Y208900D03*
X841000Y270500D03*
X846000Y270525D03*
X851000D03*
X856000D03*
X843500Y268575D03*
X853500D03*
X850750Y250750D03*
X853000Y303500D03*
X861600Y304600D03*
X845000Y303000D03*
X848500Y335800D03*
X839692Y329592D03*
X854825Y330925D03*
X850500Y356925D03*
X843843Y354342D03*
X864500Y358500D03*
X849000Y399000D03*
X850390Y385878D03*
X847390D03*
X859253D03*
X856253D03*
X865542Y385771D03*
X859342Y413916D03*
X856342D03*
X865342D03*
X862342D03*
Y411150D03*
X865342D03*
X856342D03*
X859342D03*
X853619Y411097D03*
Y413863D03*
Y416863D03*
X862342Y408150D03*
Y405150D03*
X865342Y408150D03*
Y405150D03*
X856342D03*
Y408150D03*
X859342Y405150D03*
Y408150D03*
X853619Y408097D03*
Y405097D03*
X859342Y416916D03*
X856342D03*
X865342D03*
X862342D03*
X856257Y474684D03*
Y480503D03*
Y477684D03*
X859257Y474684D03*
Y480503D03*
Y477684D03*
X862257Y474684D03*
Y480503D03*
Y477684D03*
X859257Y483503D03*
X862311Y486332D03*
X862257Y483503D03*
X853257Y474684D03*
Y480503D03*
Y477684D03*
X853311Y486332D03*
X853257Y483503D03*
X856311Y486332D03*
X856257Y483503D03*
X859311Y486332D03*
X865311D03*
X865257Y483503D03*
Y474684D03*
Y480503D03*
Y477684D03*
X854082Y505410D03*
X848263D03*
X851082D03*
X854082Y508410D03*
X848263D03*
X851082D03*
X854082Y511410D03*
X848263D03*
X851082D03*
X854082Y514410D03*
X848263D03*
X851082D03*
X845263Y508410D03*
X842434Y511464D03*
X845263Y511410D03*
X842434Y514464D03*
X845263Y514410D03*
X854082Y502410D03*
X848263D03*
X851082D03*
X842434Y502464D03*
X845263Y502410D03*
X842434Y505464D03*
X845263Y505410D03*
X842434Y508464D03*
Y523464D03*
X845263Y523410D03*
X854082Y517410D03*
X848263D03*
X851082D03*
Y520410D03*
X848263D03*
X854082D03*
X842434Y517464D03*
X845263Y517410D03*
Y520410D03*
X842434Y520464D03*
X854082Y523410D03*
X848263D03*
X851082D03*
X868000Y271500D03*
X867000Y291260D03*
X870000Y304525D03*
X875000D03*
X880000D03*
X888000Y283475D03*
X870000Y312788D03*
X880000Y312855D03*
X875000Y347273D03*
X874000Y358475D03*
X885500Y352925D03*
X869000Y360500D03*
X893091Y385771D03*
X874405D03*
X877405D03*
X868542D03*
X884228D03*
X887228D03*
X868342Y416916D03*
X871342D03*
X868342Y413916D03*
X871342D03*
Y411150D03*
X868342D03*
X874172Y408096D03*
Y405096D03*
Y416862D03*
Y413862D03*
Y411096D03*
X871342Y405150D03*
Y408150D03*
X868342Y405150D03*
Y408150D03*
X868311Y486332D03*
X868257Y483503D03*
Y477684D03*
Y480503D03*
Y474684D03*
X871311Y486332D03*
X874311D03*
X874257Y477684D03*
Y480503D03*
Y474684D03*
X871257Y483503D03*
Y474684D03*
Y480503D03*
Y477684D03*
X874257Y483503D03*
X909000Y283475D03*
X904500Y292000D03*
X915000Y322425D03*
X912000Y332425D03*
X905941Y320366D03*
X903500Y327975D03*
X916260Y355000D03*
X910992Y361075D03*
X920000Y355525D03*
X923740Y345500D03*
X896091Y385771D03*
X912525Y385877D03*
X906662D03*
X903662D03*
X922454Y385771D03*
X915525Y385877D03*
X911776Y507184D03*
Y510184D03*
Y501184D03*
Y504184D03*
X923595Y498461D03*
X920595D03*
X920542Y504184D03*
X923542D03*
X920542Y501184D03*
X923542D03*
Y510184D03*
X920542D03*
X923542Y507184D03*
X920542D03*
Y513184D03*
X923542D03*
X911829Y498461D03*
X914829D03*
X917595D03*
X917542Y504184D03*
Y501184D03*
Y510184D03*
Y507184D03*
Y513184D03*
X914776D03*
Y507184D03*
Y510184D03*
Y501184D03*
Y504184D03*
X911776Y513184D03*
X920542Y516184D03*
X923542D03*
X917542D03*
X914776D03*
X911776D03*
X917596Y519014D03*
X914830D03*
X911830D03*
X923596D03*
X920596D03*
X940575Y304000D03*
X926000Y283475D03*
X937516Y300075D03*
X947000Y302475D03*
X940000Y283800D03*
X930500Y315460D03*
X943172Y310885D03*
X943171Y315385D03*
X935516Y361075D03*
X927000Y357925D03*
X943885Y352385D03*
X933357Y344843D03*
X933196Y353360D03*
X925454Y385771D03*
X944247Y385877D03*
X941247D03*
X931317Y385771D03*
X934317D03*
X950110Y385877D03*
X953110D03*
X1022575Y100925D03*
Y115500D03*
X1034500Y145000D03*
X1037000Y146300D03*
X1037500Y142000D03*
X1036500Y153500D03*
X1043936Y145745D03*
X1019040Y157310D03*
X1019030Y160330D03*
X1022168Y155877D03*
Y161783D03*
X1017909Y151424D03*
X1017837Y154280D03*
X1024340Y146600D03*
X1016614Y187267D03*
Y190267D03*
X1036500Y172000D03*
Y163000D03*
X1039016Y189075D03*
Y183027D03*
X1039538Y179208D03*
X1039016Y185925D03*
X1022000Y171200D03*
X1019700Y166600D03*
X1016614Y197767D03*
X1057525Y130500D03*
X1049356Y143900D03*
X1047159Y141487D03*
X1054500Y148500D03*
X1048000Y153500D03*
X1057525Y134000D03*
Y138600D03*
X1073154Y140800D03*
X1057500Y155877D03*
X1070715Y146500D03*
X1063500Y159814D03*
X1048000Y172000D03*
Y163000D03*
X1060500Y164500D03*
X1062500Y191500D03*
X1067000D03*
X1070000D03*
X1058000D03*
X1053830Y191670D03*
X1060000Y249000D03*
X1063000D03*
X1066000D03*
Y246000D03*
X1063000D03*
X1060000D03*
X1066000Y243000D03*
X1063000D03*
X1060000D03*
X1069000Y246000D03*
Y243000D03*
X1072000Y246000D03*
Y243000D03*
X1060000Y252000D03*
X1063000D03*
X1066000D03*
Y258000D03*
X1063000D03*
X1060000D03*
X1066000Y255000D03*
X1063000D03*
X1060000D03*
X1069000Y258000D03*
Y255000D03*
X1072000Y258000D03*
Y255000D03*
X1067701Y270442D03*
X1061600Y276242D03*
X1060000Y296500D03*
X1063000D03*
X1066000D03*
Y293500D03*
X1063000D03*
X1060000D03*
X1069000D03*
X1060000Y299500D03*
X1063000D03*
X1066000D03*
Y305500D03*
X1063000D03*
X1060000D03*
X1066000Y302500D03*
X1063000D03*
X1060000D03*
X1069000Y305500D03*
Y302500D03*
X1066000Y290500D03*
X1063000D03*
X1060000D03*
X1069000D03*
X1072000Y293500D03*
Y305500D03*
Y302500D03*
Y290500D03*
X1066000Y338000D03*
X1063000D03*
X1060000D03*
X1069000D03*
X1072000D03*
X1067679Y317942D03*
X1061600Y323742D03*
X1060000Y344000D03*
X1063000D03*
X1066000D03*
X1060000Y347000D03*
X1063000D03*
X1066000D03*
Y341000D03*
X1063000D03*
X1060000D03*
X1066000Y353000D03*
X1063000D03*
X1060000D03*
X1066000Y350000D03*
X1063000D03*
X1060000D03*
X1069000Y353000D03*
Y350000D03*
Y341000D03*
X1072000Y353000D03*
Y350000D03*
Y341000D03*
X1067707Y365442D03*
X1061600Y359642D03*
X1066000Y397500D03*
X1063000D03*
X1060000D03*
X1069000D03*
X1060000Y391500D03*
X1063000D03*
X1066000D03*
X1060000Y394500D03*
X1063000D03*
X1066000D03*
Y388500D03*
X1063000D03*
X1060000D03*
X1066000Y385500D03*
X1063000D03*
X1060000D03*
X1069000Y388500D03*
Y385500D03*
X1072000Y397500D03*
Y388500D03*
Y385500D03*
X1066000Y400500D03*
X1063000D03*
X1060000D03*
X1069000D03*
X1072000D03*
X1067531Y412942D03*
X1060984Y418742D03*
X1066000Y433000D03*
X1063000D03*
X1060000D03*
X1069000D03*
X1060000Y439000D03*
X1063000D03*
X1066000D03*
X1060000Y442000D03*
X1063000D03*
X1066000D03*
Y436000D03*
X1063000D03*
X1060000D03*
X1069000D03*
X1072000Y433000D03*
Y436000D03*
X1066000Y448000D03*
X1063000D03*
X1060000D03*
X1066000Y445000D03*
X1063000D03*
X1060000D03*
X1069000Y448000D03*
Y445000D03*
X1072000Y448000D03*
Y445000D03*
X1069000Y480500D03*
Y483500D03*
X1060000Y480500D03*
X1063000D03*
X1066000D03*
X1060000Y483500D03*
X1063000D03*
X1066000D03*
Y486500D03*
X1063000D03*
X1060000D03*
X1072000Y480500D03*
Y483500D03*
X1067730Y460352D03*
X1061600Y466242D03*
X1069000Y492500D03*
Y495500D03*
X1060000Y492500D03*
X1063000D03*
X1066000D03*
X1060000Y495500D03*
X1063000D03*
X1066000D03*
Y489500D03*
X1063000D03*
X1060000D03*
X1072000Y492500D03*
Y495500D03*
X1067866Y507629D03*
X1061600Y513742D03*
X1066500Y538000D03*
Y541000D03*
X1069500D03*
X1066500Y544000D03*
X1069500D03*
Y538000D03*
Y547000D03*
Y550000D03*
X1066500Y547000D03*
Y550000D03*
Y553000D03*
X1069500D03*
X1092000Y82500D03*
X1087000Y100000D03*
X1073200Y90900D03*
X1077200D03*
X1084325Y130197D03*
X1094493Y151856D03*
X1073154Y137800D03*
X1082000Y143600D03*
X1092000Y159500D03*
X1094500Y143144D03*
X1084401Y159260D03*
X1094024Y179500D03*
X1085000Y184575D03*
X1079500D03*
X1085525Y167500D03*
Y171000D03*
Y174500D03*
Y164000D03*
X1087500Y198000D03*
Y201000D03*
X1097500Y203700D03*
X1100000D03*
X1073500Y191500D03*
X1086500Y356000D03*
X1080418Y373600D03*
X1086500Y403500D03*
X1074316Y406925D03*
X1123000Y120816D03*
X1126000D03*
X1131500D03*
X1115800Y126600D03*
X1130125Y135940D03*
X1126075Y135973D03*
X1121238Y144500D03*
X1108500Y136500D03*
X1104500Y136524D03*
X1120524Y138457D03*
X1129000Y157000D03*
X1120200D03*
X1115425Y138925D03*
X1119000Y189500D03*
X1111100Y163749D03*
X1123500Y187000D03*
X1108000Y172000D03*
X1113368Y171619D03*
X1110800Y170000D03*
X1113129Y165719D03*
X1114500Y188700D03*
X1120200Y176500D03*
Y166500D03*
X1129000D03*
Y176500D03*
X1108821Y166800D03*
X1125918Y195418D03*
X1129068Y195500D03*
X1133000Y198000D03*
X1117206Y231741D03*
X1117290Y224241D03*
X1106189D03*
X1106106Y231741D03*
X1134500Y120816D03*
X1158200Y137700D03*
X1136300Y161100D03*
X1140000D03*
X1160200Y175982D03*
X1152781Y165719D03*
X1136300Y172300D03*
X1140000D03*
X1140336Y183560D03*
X1143490D03*
X1152500Y186500D03*
X1158000Y179000D03*
X1162700Y175959D03*
X1183021Y165952D03*
X1185521D03*
X1188600Y166000D03*
X1188618Y162782D03*
X1185521Y162952D03*
X1183021D03*
X1180521D03*
Y165952D03*
X1177521D03*
Y162952D03*
X1167600Y184500D03*
Y180500D03*
X1174500Y214000D03*
Y211000D03*
Y208000D03*
Y205000D03*
X1171500D03*
Y208000D03*
Y211000D03*
Y214000D03*
X1179651Y305942D03*
Y309942D03*
X1165070Y328750D03*
X1193411D03*
X1179411Y334250D03*
Y337750D03*
Y330750D03*
Y327250D03*
X1180986Y349234D03*
X1177836D03*
X1179877Y452442D03*
Y448442D03*
X1165190Y471250D03*
X1179500Y476750D03*
Y480250D03*
Y469750D03*
Y473250D03*
X1181075Y491734D03*
X1177925D03*
X1193840Y471250D03*
G54D12*
X72836Y47244D03*
Y535433D03*
X466536Y47244D03*
X860237D03*
X943225Y228000D03*
X985225Y542500D03*
G54D35*
X268000Y240000D03*
X312500D03*
X357000D03*
X428500D03*
X472500D03*
X516500D03*
X578500D03*
X622500D03*
X666500D03*
X735981D03*
X779981D03*
X823981D03*
G54D16*
X38780Y272598D03*
Y279291D03*
Y292598D03*
Y299291D03*
X48780Y272598D03*
Y279291D03*
Y292598D03*
Y299291D03*
G54D25*
X165350Y220098D03*
X162850D03*
Y227185D03*
Y230728D03*
X165350Y223642D03*
Y227185D03*
Y230728D03*
X162850Y223642D03*
G54D28*
X165539Y539000D03*
X213539D03*
X261539D03*
X323019D03*
X371019D03*
X419019D03*
X480500D03*
X528500D03*
X576500D03*
X637981D03*
X685981D03*
X733981D03*
G54D17*
X33780Y334724D03*
Y314724D03*
X38780Y319724D03*
Y329724D03*
Y339724D03*
X33780Y344724D03*
X38780Y349724D03*
X48780Y319724D03*
Y329724D03*
Y339724D03*
X43780Y314724D03*
Y324724D03*
Y334724D03*
X48780Y349724D03*
X43780Y344724D03*
G54D23*
X155140Y240230D03*
X172934Y219110D03*
X172712Y222263D03*
X183815Y220903D03*
X808500Y272925D03*
X831000Y260500D03*
X836000D03*
X825941Y339560D03*
X835610Y355590D03*
X841000Y260525D03*
X865000Y313200D03*
X878000Y358475D03*
X883000Y358500D03*
X1070400Y123200D03*
X1067600D03*
X1111452Y544000D03*
Y541000D03*
X1114452Y544000D03*
Y541000D03*
Y538000D03*
X1111452D03*
X1120669Y544000D03*
Y541000D03*
X1123669Y544000D03*
Y541000D03*
Y538000D03*
X1120669D03*
X1114452Y553000D03*
X1111452D03*
X1114452Y550000D03*
X1111452D03*
X1114452Y547000D03*
X1111452D03*
X1123669Y553000D03*
X1120669D03*
X1123669Y550000D03*
X1120669D03*
X1123669Y547000D03*
X1120669D03*
G54D27*
X180539Y498000D03*
X183539D03*
X228539D03*
X231539D03*
X276539D03*
X279539D03*
X338019D03*
X341019D03*
X386019D03*
X389019D03*
X434019D03*
X437019D03*
X498500D03*
X495500D03*
X546500D03*
X543500D03*
X594500D03*
X591500D03*
X655981D03*
X652981D03*
X703981D03*
X700981D03*
X748981D03*
X751981D03*
X826000Y260525D03*
X848075Y306500D03*
X912500Y327975D03*
X1159710Y306037D03*
X1156710D03*
X1159710Y303037D03*
X1156710D03*
X1159710Y300037D03*
X1156710D03*
X1159710Y297037D03*
X1156710D03*
Y294037D03*
X1159710D03*
Y309037D03*
X1156710D03*
X1159710Y312037D03*
X1156710D03*
X1159710Y321037D03*
X1156710D03*
X1159710Y318037D03*
X1156710D03*
X1159710Y315037D03*
X1156710D03*
X1159799Y448537D03*
X1156799D03*
X1159799Y445537D03*
X1156799D03*
X1159799Y442537D03*
X1156799D03*
X1159799Y439537D03*
X1156799D03*
Y436537D03*
X1159799D03*
Y454537D03*
X1156799D03*
X1159799Y451537D03*
X1156799D03*
X1159799Y457537D03*
X1156799D03*
X1159799Y463537D03*
X1156799D03*
X1159799Y460537D03*
X1156799D03*
X1162710Y306037D03*
Y303037D03*
Y300037D03*
Y297037D03*
Y294037D03*
Y309037D03*
Y312037D03*
Y321037D03*
Y318037D03*
Y315037D03*
X1162799Y448537D03*
Y445537D03*
Y442537D03*
Y439537D03*
Y436537D03*
Y454537D03*
Y451537D03*
Y457537D03*
Y463537D03*
Y460537D03*
G54D30*
X208071Y267204D03*
X200197D03*
X215945D03*
X231693D03*
X223819D03*
X239567D03*
X247441D03*
X357677D03*
X365551D03*
X373425D03*
X389173D03*
X381299D03*
X404921D03*
X397047D03*
X523032D03*
X515158D03*
X530906D03*
X538780D03*
X546654D03*
X562402D03*
X554528D03*
X680513D03*
X672639D03*
X688387D03*
X704135D03*
X696261D03*
X712009D03*
X719883D03*
G54D33*
X223819Y477204D03*
X253819D03*
X381299D03*
X411299D03*
X538780D03*
X568780D03*
X696261D03*
X726261D03*
G54D38*
X411752Y129685D03*
X401752D03*
X411752Y139685D03*
Y149685D03*
Y159685D03*
X401752Y139685D03*
Y149685D03*
Y159685D03*
X446752Y129685D03*
X436752D03*
X446752Y139685D03*
Y149685D03*
Y159685D03*
X436752Y139685D03*
Y149685D03*
Y159685D03*
X481752Y129685D03*
X471752D03*
X481752Y139685D03*
Y149685D03*
Y159685D03*
X471752Y139685D03*
Y149685D03*
Y159685D03*
X712559Y129408D03*
Y119408D03*
Y149408D03*
Y139408D03*
X722559Y129408D03*
Y119408D03*
X747559Y129408D03*
Y119408D03*
X722559Y149408D03*
Y139408D03*
X747559Y149408D03*
Y139408D03*
X757559Y129408D03*
Y119408D03*
Y149408D03*
Y139408D03*
X782559Y129408D03*
Y119408D03*
X792559Y129408D03*
Y119408D03*
X782559Y149408D03*
Y139408D03*
X792559Y149408D03*
Y139408D03*
X812559Y119408D03*
Y129408D03*
X822559Y119408D03*
Y129408D03*
X832559Y119408D03*
Y129408D03*
X812559Y149408D03*
X822559Y139408D03*
Y149408D03*
X832559Y139408D03*
Y149408D03*
X1226024Y286929D03*
X1236024D03*
X1246024D03*
X1256024D03*
G54D43*
X1011000Y98000D03*
Y118000D03*
X1161000Y90400D03*
X1151000D03*
X1171000D03*
G54D40*
X766498Y602542D03*
X766604Y630687D03*
X766498Y612542D03*
X766604Y640687D03*
X1082833Y602542D03*
Y612542D03*
Y630687D03*
Y640687D03*
G54D37*
X296752Y129685D03*
Y139685D03*
Y149685D03*
Y159685D03*
X331752Y129685D03*
X306752D03*
X331752Y139685D03*
Y149685D03*
Y159685D03*
X306752Y139685D03*
Y149685D03*
Y159685D03*
X341752Y129685D03*
Y139685D03*
Y149685D03*
Y159685D03*
X376752Y129685D03*
X366752D03*
X376752Y139685D03*
Y149685D03*
Y159685D03*
X366752Y139685D03*
Y149685D03*
Y159685D03*
X1226024Y221929D03*
X1236024D03*
X1246024D03*
X1226024Y231929D03*
X1236024D03*
X1246024D03*
X1226024Y256929D03*
X1236024D03*
X1246024D03*
X1226024Y266929D03*
X1236024D03*
X1246024D03*
X1226024Y306929D03*
X1236024D03*
X1246024D03*
X1226024Y316929D03*
X1236024D03*
X1246024D03*
X1226024Y341929D03*
X1236024D03*
X1246024D03*
X1226024Y351929D03*
X1236024D03*
X1246024D03*
X1256024Y221929D03*
Y231929D03*
Y256929D03*
Y266929D03*
Y306929D03*
Y316929D03*
Y341929D03*
Y351929D03*
G54D26*
X178819Y277204D03*
X193819D03*
X336299D03*
X351299D03*
X493780D03*
X508780D03*
X651261D03*
X666261D03*
G54D44*
X1011000Y108000D03*
G54D29*
X185224Y539000D03*
X233224D03*
X281224D03*
X342704D03*
X390704D03*
X438704D03*
X500185D03*
X548185D03*
X596185D03*
X657666D03*
X705666D03*
X753666D03*
G54D46*
X1096017Y635687D03*
G54D45*
Y607542D03*
G54D36*
X253819Y277204D03*
X268819D03*
X411299D03*
X426299D03*
X568780D03*
X583780D03*
X726261D03*
X741261D03*
G54D13*
X118111Y47244D03*
Y535433D03*
X511811Y47244D03*
X905512D03*
X988500Y228000D03*
X1030500Y542500D03*
G54D11*
X19685Y-614173D03*
Y636929D03*
X619685D03*
X1271654Y-614173D03*
Y636929D03*
G54D14*
X19922Y214173D03*
Y367716D03*
G54D24*
X175000Y100500D03*
X877510Y558620D03*
X964460Y16950D03*
G54D21*
X82795Y99724D03*
Y482205D03*
G54D32*
X249252Y129685D03*
X529252D03*
X665059Y149408D03*
X980059D03*
X1226024Y174429D03*
Y399429D03*
G54D19*
X60630Y99724D03*
Y482205D03*
X108858Y99724D03*
Y482205D03*
G54D22*
X153480Y213350D03*
X941035Y344474D03*
X1097100Y35582D03*
Y38582D03*
X1099600D03*
Y35582D03*
X1102100D03*
Y38582D03*
X1096961Y18126D03*
Y21126D03*
X1099461D03*
Y18126D03*
X1101961D03*
Y21126D03*
X1097101Y53737D03*
Y56737D03*
X1099601D03*
Y53737D03*
X1102101D03*
Y56737D03*
X1125170Y35582D03*
Y38582D03*
X1127670D03*
Y35582D03*
X1130170D03*
Y38582D03*
X1104600Y35582D03*
Y38582D03*
X1107100Y35582D03*
Y38582D03*
X1104461Y18126D03*
Y21126D03*
X1106961Y18126D03*
Y21126D03*
X1130031D03*
Y18126D03*
X1127531D03*
Y21126D03*
X1125031D03*
Y18126D03*
X1104601Y53737D03*
Y56737D03*
X1107101Y53737D03*
Y56737D03*
X1132670Y35582D03*
X1135170D03*
Y38582D03*
X1132670D03*
X1135031Y21126D03*
Y18126D03*
X1132531Y21126D03*
Y18126D03*
X1132950Y82867D03*
Y85867D03*
X1135450D03*
Y82867D03*
X1137950D03*
X1140450D03*
X1142950D03*
Y85867D03*
X1140450D03*
X1137950D03*
X1183321Y123652D03*
X1185821D03*
X1188321D03*
Y120652D03*
X1185821D03*
X1183321D03*
X1180821D03*
Y123652D03*
X1178321D03*
Y120652D03*
G54D10*
X3005Y19808D03*
Y34808D03*
Y59808D03*
X7595Y128373D03*
X3005Y145238D03*
Y165238D03*
Y185238D03*
Y205238D03*
Y225238D03*
Y245238D03*
Y265238D03*
Y285238D03*
Y305238D03*
Y325238D03*
Y345238D03*
Y365238D03*
Y385238D03*
Y405238D03*
Y425238D03*
Y445238D03*
X3023Y524312D03*
Y549312D03*
X4540Y566003D03*
X34582Y3004D03*
X14811Y3732D03*
X12767Y72072D03*
X27271Y127298D03*
X19558Y454589D03*
X9913Y510026D03*
X20498Y575739D03*
X54582Y3004D03*
X39549Y454916D03*
X40498Y575739D03*
X60498D03*
X94582Y3004D03*
X74582D03*
X80498Y575739D03*
X114582Y3004D03*
X100498Y575739D03*
X120498D03*
X154582Y3004D03*
X134582D03*
X140400Y258360D03*
X143400D03*
X140400Y261360D03*
X143400D03*
X140400Y255360D03*
X143400D03*
X140498Y575739D03*
X174582Y3004D03*
X184349Y212651D03*
X173265Y340552D03*
X183539Y518000D03*
X180539D03*
X214582Y3004D03*
X194582D03*
X189760Y242100D03*
Y245100D03*
X192760Y242100D03*
Y245100D03*
X195760Y242100D03*
Y245100D03*
X198760Y242100D03*
Y245100D03*
X201760Y242100D03*
Y245100D03*
X208071Y305975D03*
X234582Y3004D03*
X246000Y238500D03*
X242500Y243000D03*
Y247500D03*
X218500Y305000D03*
X226975D03*
X235975D03*
X239567Y305975D03*
X223819Y445025D03*
X231539Y518000D03*
X228539D03*
X254582Y3004D03*
X246000Y235500D03*
X294582Y3004D03*
X274582D03*
X297000Y206000D03*
Y203500D03*
Y198500D03*
Y196000D03*
X290720Y340338D03*
X279539Y518000D03*
X276539D03*
X314582Y3004D03*
X318500Y206000D03*
Y203500D03*
Y198500D03*
Y196000D03*
X313571Y340552D03*
X354582Y3004D03*
X334582D03*
X340000Y206000D03*
Y203500D03*
Y198500D03*
Y196000D03*
X361500Y206000D03*
Y203500D03*
Y198500D03*
Y196000D03*
X341019Y518000D03*
X338019D03*
X374582Y3004D03*
X383000Y206000D03*
Y203500D03*
Y198500D03*
Y196000D03*
X375475Y305000D03*
X383975D03*
X365551Y305975D03*
X381299Y445025D03*
X389019Y518000D03*
X386019D03*
X414582Y3004D03*
X394582D03*
X404500Y206000D03*
Y203500D03*
Y198500D03*
Y196000D03*
X402000Y235000D03*
Y238000D03*
X398500Y247000D03*
Y242500D03*
X393000Y305000D03*
X397047Y305975D03*
X434582Y3004D03*
X426000Y206000D03*
Y203500D03*
Y198500D03*
Y196000D03*
X447255Y340339D03*
X430019Y444260D03*
X432019Y452025D03*
X437019Y518000D03*
X434019D03*
X474582Y3004D03*
X454582D03*
X473095Y340339D03*
X494582Y3004D03*
X498500Y518000D03*
X495500D03*
X534582Y3004D03*
X514582D03*
X533475Y305500D03*
X523032Y305975D03*
X538780Y445025D03*
X554582Y3004D03*
X555500Y239000D03*
Y236000D03*
X552000Y243500D03*
Y247000D03*
X542475Y305500D03*
X551475D03*
X554528Y305975D03*
X545063Y340339D03*
X549500Y445024D03*
X546500Y518000D03*
X543500D03*
X594582Y3004D03*
X574582D03*
X587500Y444260D03*
X589500Y446500D03*
X594500Y518000D03*
X591500D03*
X614582Y3004D03*
X604500Y205500D03*
Y203000D03*
Y198000D03*
Y195500D03*
X626000Y205500D03*
Y203000D03*
Y198000D03*
Y195500D03*
X654582Y3004D03*
X634582D03*
X647975Y37000D03*
X660200Y56800D03*
X655300D03*
X652300D03*
X647500Y205500D03*
Y203000D03*
Y198000D03*
Y195500D03*
X655981Y518000D03*
X652981D03*
X674582Y3004D03*
X684525Y32500D03*
Y36500D03*
X683600Y56800D03*
X679000D03*
X676000D03*
X686500D03*
X671100D03*
X668100D03*
X663200D03*
X669000Y205500D03*
Y203000D03*
Y198000D03*
Y195500D03*
X680513Y305975D03*
X714582Y3004D03*
X694582D03*
X699500Y34500D03*
X696900Y53300D03*
X694200D03*
X691400D03*
X689900Y56600D03*
X693000D03*
X696100Y56700D03*
X706000Y61975D03*
X690500Y205500D03*
Y203000D03*
Y198000D03*
Y195500D03*
X711990D03*
Y198000D03*
Y203000D03*
Y205500D03*
X709500Y247000D03*
X709481Y243500D03*
X712981Y236000D03*
Y239000D03*
X712009Y305975D03*
X708956Y305500D03*
X690956D03*
X700000D03*
X696261Y445024D03*
X703981Y518000D03*
X700981D03*
X734582Y3004D03*
X733490Y195500D03*
Y198000D03*
Y203000D03*
Y205500D03*
X732100Y332400D03*
X742500Y361500D03*
X774582Y3004D03*
X754582D03*
X761560Y38500D03*
X758760D03*
X756160D03*
X761560Y30000D03*
X758760D03*
X756160D03*
X758900Y27400D03*
X761560Y55500D03*
X758760D03*
X756160D03*
X761560Y47000D03*
X758760D03*
X756160D03*
X761560Y64000D03*
X758760D03*
X756160D03*
X751981Y518000D03*
X748981D03*
X794582Y3004D03*
X797854Y259539D03*
X786500Y336484D03*
X834582Y3004D03*
X814582D03*
X809500Y259430D03*
X819500Y329000D03*
X827500D03*
X813975Y362000D03*
Y357000D03*
X854582Y3004D03*
X849490Y196000D03*
Y198500D03*
Y203500D03*
Y206000D03*
X846000Y260525D03*
X851000D03*
X856000D03*
X837575Y321000D03*
X844760Y336077D03*
X850500Y360075D03*
Y366000D03*
X847500D03*
X856500D03*
X859500D03*
X865500D03*
X894582Y3004D03*
X874582D03*
X894500Y283475D03*
X884000D03*
X877500D03*
X893363Y298740D03*
X883000Y293925D03*
X877500Y366000D03*
X874500D03*
X884000D03*
X887000D03*
X893500D03*
X868500D03*
X914582Y3004D03*
X915500Y283475D03*
X914500Y292000D03*
X905000Y283475D03*
X905941Y306500D03*
X916260Y337077D03*
X908000Y327975D03*
X896500Y366000D03*
X906000D03*
X903000D03*
X912500D03*
X915500D03*
X922000D03*
X901063Y352340D03*
X934582Y3004D03*
X933000Y293476D03*
X940000D03*
X947000D03*
X933196Y309910D03*
X925000Y366000D03*
X944000D03*
X941000D03*
X934500D03*
X950500D03*
X953500D03*
X931500D03*
X927000Y361075D03*
X940498Y575739D03*
X974582Y3004D03*
X954582D03*
X960498Y575739D03*
X980498D03*
X994582Y3004D03*
X1000498Y575739D03*
X1034582Y3004D03*
X1014582D03*
X1034500Y142000D03*
X1020498Y575739D03*
X1040498D03*
X1054582Y3004D03*
X1068900Y110000D03*
X1065000Y156425D03*
X1070715Y178585D03*
X1060498Y575739D03*
X1094582Y3004D03*
X1074582D03*
X1091000Y99500D03*
X1095100D03*
X1073200Y126000D03*
Y128800D03*
Y123200D03*
X1084740Y108000D03*
X1100075Y139925D03*
X1084260Y152600D03*
X1101903Y285019D03*
X1101796Y331894D03*
X1090500Y376500D03*
X1090443Y417343D03*
X1080498Y575739D03*
X1100498D03*
X1114582Y3004D03*
X1113000Y101240D03*
X1119500Y86000D03*
Y83000D03*
X1113500Y147500D03*
X1118774Y284699D03*
X1112902D03*
X1110019Y284806D03*
X1104786Y284912D03*
X1121657Y284592D03*
X1118667Y331574D03*
X1112795D03*
X1109912Y331681D03*
X1104679Y331787D03*
X1121550Y331467D03*
X1104009Y427245D03*
X1120880Y426925D03*
X1115008D03*
X1112125Y427032D03*
X1106892Y427138D03*
X1123763Y426818D03*
X1103800Y474339D03*
X1106683Y474232D03*
X1111916Y474126D03*
X1114799Y474019D03*
X1120671D03*
X1123554Y473912D03*
X1120498Y575739D03*
X1154582Y3004D03*
X1134582D03*
X1155000Y124913D03*
X1159300Y129700D03*
X1141500Y124425D03*
Y120500D03*
X1154000Y151500D03*
X1141500Y134575D03*
X1138203Y266860D03*
Y260860D03*
Y263860D03*
X1135203Y260860D03*
Y263860D03*
Y266860D03*
X1138203Y257860D03*
Y254860D03*
X1135203Y257860D03*
Y254860D03*
X1135403Y302360D03*
Y305360D03*
X1138403Y302360D03*
Y305360D03*
X1135403Y308360D03*
X1138403D03*
X1135403Y314360D03*
Y311360D03*
X1138403D03*
Y314360D03*
Y361979D03*
X1135403D03*
X1138403Y358979D03*
X1135403D03*
X1138403Y355979D03*
X1135403D03*
X1138403Y352979D03*
X1135403D03*
X1138403Y349979D03*
X1135403D03*
X1135190Y396965D03*
X1138190D03*
X1135190Y399965D03*
X1138190D03*
X1135190Y402965D03*
Y405965D03*
Y408965D03*
X1138190Y402965D03*
Y405965D03*
Y408965D03*
X1135404Y457228D03*
Y454228D03*
Y451228D03*
Y445228D03*
Y448228D03*
X1138404Y454228D03*
Y451228D03*
Y445228D03*
Y448228D03*
Y457228D03*
X1135622Y485732D03*
Y470732D03*
Y467732D03*
Y479732D03*
Y476732D03*
Y473732D03*
Y482732D03*
X1138622D03*
Y473732D03*
Y476732D03*
Y479732D03*
Y470732D03*
Y485732D03*
Y467732D03*
X1140498Y575739D03*
X1160498D03*
X1174582Y3004D03*
X1177475Y111500D03*
X1179500Y105500D03*
X1180498Y575739D03*
X1214582Y3004D03*
X1194582D03*
X1203887Y306894D03*
X1200887D03*
X1197887D03*
X1203887Y303894D03*
X1200887D03*
X1197887D03*
X1203887Y300894D03*
X1200887D03*
X1197887D03*
X1203887Y297894D03*
X1200887D03*
X1197887D03*
X1203887Y294894D03*
X1200887D03*
X1197887D03*
Y321894D03*
X1200887D03*
X1203887D03*
Y318894D03*
X1200887D03*
X1197887D03*
X1203887Y315894D03*
X1200887D03*
X1197887D03*
X1203887Y312894D03*
X1200887D03*
X1197887D03*
X1203887Y309894D03*
X1200887D03*
X1197887D03*
X1197976Y437394D03*
X1200976D03*
X1203976D03*
X1197976Y440394D03*
X1200976D03*
X1203976D03*
X1197976Y443394D03*
X1200976D03*
X1203976D03*
X1197976Y446394D03*
X1200976D03*
X1203976D03*
X1197976Y449394D03*
X1200976D03*
X1203976D03*
X1197976Y452394D03*
X1200976D03*
X1203976D03*
X1197976Y455394D03*
X1200976D03*
X1203976D03*
X1197976Y464394D03*
X1200976D03*
X1203976D03*
X1197976Y458394D03*
X1200976D03*
X1203976D03*
X1197976Y461394D03*
X1200976D03*
X1203976D03*
X1200498Y575739D03*
X1220498D03*
X1234582Y3004D03*
X1240498Y575739D03*
X1277657Y4128D03*
X1254582Y3004D03*
X1260498Y575739D03*
X1279438Y573806D03*
X1286766Y12634D03*
X1288331Y30962D03*
Y70962D03*
Y50962D03*
Y90962D03*
Y130962D03*
Y110962D03*
Y150962D03*
Y190962D03*
Y170962D03*
Y210962D03*
Y230962D03*
Y270962D03*
Y250962D03*
Y290962D03*
Y330962D03*
Y310962D03*
Y350962D03*
Y390962D03*
Y370962D03*
Y410962D03*
Y450962D03*
Y430962D03*
Y470962D03*
Y510962D03*
Y490962D03*
Y530962D03*
X1287616Y563889D03*
X1288331Y550962D03*
G54D42*
X812559Y139408D03*
X852559Y129408D03*
Y119408D03*
X862559Y129408D03*
Y119408D03*
X852559Y149408D03*
Y139408D03*
X862559Y149408D03*
Y139408D03*
X887559Y129408D03*
Y119408D03*
Y149408D03*
Y139408D03*
X897559Y129408D03*
Y119408D03*
X922559Y129408D03*
Y119408D03*
X897559Y149408D03*
Y139408D03*
X922559Y149408D03*
Y139408D03*
X932559Y129408D03*
Y119408D03*
Y149408D03*
Y139408D03*
G54D48*
X1226024Y174429D03*
Y399429D03*
G54D18*
X33780Y324724D03*
G54D34*
X268000Y220315D03*
X312500D03*
X357000D03*
X428500D03*
X472500D03*
X516500D03*
X578500D03*
X622500D03*
X666500D03*
X735981D03*
X779981D03*
X823981D03*
G54D15*
X38780Y232598D03*
Y239291D03*
Y252598D03*
Y259291D03*
X48780Y232598D03*
Y239291D03*
Y252598D03*
Y259291D03*
G54D47*
X1240158Y57480D03*
Y521260D03*
G54D31*
X193819Y477204D03*
X351299D03*
X508780D03*
X666261D03*
G54D39*
X753314Y607542D03*
G54D41*
X753420Y635687D03*
%LPC*%
G75*
G54D50*
G01X-297025Y-1013390D02*
Y1828909D01*
X3691357D01*
Y-1013390D01*
X-297025D01*
G01X4093Y-769672D02*
Y-844672D01*
X504093D01*
Y-769672D01*
X4093D01*
G01X16093Y-834672D02*
Y-839672D01*
G01X14636Y-834672D02*
X17550D01*
G01X22460Y-839672D02*
X19926D01*
Y-834672D01*
X22460D01*
G01X21446Y-837089D02*
X19926D01*
G01X25026Y-834672D02*
Y-839672D01*
X27560D01*
G01X31393Y-839839D02*
X31266Y-839755D01*
Y-839589D01*
X31393Y-839505D01*
X31520Y-839589D01*
Y-839755D01*
X31393Y-839839D01*
G01Y-837589D02*
X31266Y-837505D01*
Y-837339D01*
X31393Y-837255D01*
X31520Y-837339D01*
Y-837505D01*
X31393Y-837589D01*
G01X36176Y-841339D02*
X35543Y-840505D01*
X35226Y-839672D01*
Y-836339D01*
X35543Y-835505D01*
X36176Y-834672D01*
G01X41593D02*
X41086Y-834839D01*
X40706Y-835255D01*
X40453Y-835755D01*
X40263Y-836422D01*
X40200Y-837172D01*
X40263Y-837922D01*
X40453Y-838589D01*
X40706Y-839089D01*
X41086Y-839505D01*
X41593Y-839672D01*
X42100Y-839505D01*
X42480Y-839089D01*
X42733Y-838589D01*
X42923Y-837922D01*
X42986Y-837172D01*
X42923Y-836422D01*
X42733Y-835755D01*
X42480Y-835255D01*
X42100Y-834839D01*
X41593Y-834672D01*
G01X45300Y-838672D02*
X45680Y-839255D01*
X46186Y-839589D01*
X46756Y-839672D01*
X47263Y-839589D01*
X47770Y-839172D01*
X48086Y-838672D01*
X48150Y-838172D01*
X48023Y-837589D01*
X47580Y-837172D01*
X47136Y-837005D01*
X46566D01*
G01X47136D02*
X47516Y-836755D01*
X47833Y-836339D01*
X47960Y-835839D01*
X47833Y-835339D01*
X47516Y-834922D01*
X46946Y-834672D01*
X46376Y-834755D01*
X45806Y-835089D01*
G01X52110Y-841339D02*
X52743Y-840505D01*
X53060Y-839672D01*
Y-836339D01*
X52743Y-835505D01*
X52110Y-834672D01*
G01X55500Y-838672D02*
X55880Y-839255D01*
X56386Y-839589D01*
X56956Y-839672D01*
X57463Y-839589D01*
X57970Y-839172D01*
X58286Y-838672D01*
X58350Y-838172D01*
X58223Y-837589D01*
X57780Y-837172D01*
X57336Y-837005D01*
X56766D01*
G01X57336D02*
X57716Y-836755D01*
X58033Y-836339D01*
X58160Y-835839D01*
X58033Y-835339D01*
X57716Y-834922D01*
X57146Y-834672D01*
X56576Y-834755D01*
X56006Y-835089D01*
G01X60790Y-835505D02*
X61170Y-835005D01*
X61613Y-834755D01*
X62120Y-834672D01*
X62753Y-834839D01*
X63196Y-835255D01*
X63323Y-835755D01*
X63260Y-836255D01*
X63006Y-836672D01*
X61740Y-837505D01*
X61170Y-838089D01*
X60790Y-838922D01*
X60663Y-839672D01*
X63323D01*
G01X66966D02*
X67093Y-838589D01*
X67283Y-837672D01*
X67536Y-836839D01*
X67853Y-835922D01*
X68360Y-834672D01*
X65826D01*
G01X71370Y-838005D02*
X73016D01*
G01X76090Y-835505D02*
X76470Y-835005D01*
X76913Y-834755D01*
X77420Y-834672D01*
X78053Y-834839D01*
X78496Y-835255D01*
X78623Y-835755D01*
X78560Y-836255D01*
X78306Y-836672D01*
X77040Y-837505D01*
X76470Y-838089D01*
X76090Y-838922D01*
X75963Y-839672D01*
X78623D01*
G01X81000Y-838672D02*
X81380Y-839255D01*
X81886Y-839589D01*
X82456Y-839672D01*
X82963Y-839589D01*
X83470Y-839172D01*
X83786Y-838672D01*
X83850Y-838172D01*
X83723Y-837589D01*
X83280Y-837172D01*
X82836Y-837005D01*
X82266D01*
G01X82836D02*
X83216Y-836755D01*
X83533Y-836339D01*
X83660Y-835839D01*
X83533Y-835339D01*
X83216Y-834922D01*
X82646Y-834672D01*
X82076Y-834755D01*
X81506Y-835089D01*
G01X88253Y-839672D02*
Y-834672D01*
X85910Y-838255D01*
X89076D01*
G01X91200Y-838922D02*
X91580Y-839339D01*
X92023Y-839589D01*
X92593Y-839672D01*
X93163Y-839505D01*
X93606Y-839172D01*
X93923Y-838589D01*
X93986Y-837922D01*
X93860Y-837255D01*
X93543Y-836839D01*
X93100Y-836505D01*
X92656Y-836422D01*
X92213Y-836505D01*
X91643Y-836839D01*
X91833Y-834672D01*
X93543D01*
G01X101590Y-839672D02*
Y-834672D01*
X103996D01*
G01X103110Y-837089D02*
X101590D01*
G01X106310Y-839672D02*
X107893Y-834672D01*
X109476Y-839672D01*
G01X108906Y-837922D02*
X106880D01*
G01X111663Y-839672D02*
X114323Y-834672D01*
G01X111663D02*
X114323Y-839672D01*
G01X118093Y-839839D02*
X117966Y-839755D01*
Y-839589D01*
X118093Y-839505D01*
X118220Y-839589D01*
Y-839755D01*
X118093Y-839839D01*
G01Y-837589D02*
X117966Y-837505D01*
Y-837339D01*
X118093Y-837255D01*
X118220Y-837339D01*
Y-837505D01*
X118093Y-837589D01*
G01X122876Y-841339D02*
X122243Y-840505D01*
X121926Y-839672D01*
Y-836339D01*
X122243Y-835505D01*
X122876Y-834672D01*
G01X128293D02*
X127786Y-834839D01*
X127406Y-835255D01*
X127153Y-835755D01*
X126963Y-836422D01*
X126900Y-837172D01*
X126963Y-837922D01*
X127153Y-838589D01*
X127406Y-839089D01*
X127786Y-839505D01*
X128293Y-839672D01*
X128800Y-839505D01*
X129180Y-839089D01*
X129433Y-838589D01*
X129623Y-837922D01*
X129686Y-837172D01*
X129623Y-836422D01*
X129433Y-835755D01*
X129180Y-835255D01*
X128800Y-834839D01*
X128293Y-834672D01*
G01X132000Y-838672D02*
X132380Y-839255D01*
X132886Y-839589D01*
X133456Y-839672D01*
X133963Y-839589D01*
X134470Y-839172D01*
X134786Y-838672D01*
X134850Y-838172D01*
X134723Y-837589D01*
X134280Y-837172D01*
X133836Y-837005D01*
X133266D01*
G01X133836D02*
X134216Y-836755D01*
X134533Y-836339D01*
X134660Y-835839D01*
X134533Y-835339D01*
X134216Y-834922D01*
X133646Y-834672D01*
X133076Y-834755D01*
X132506Y-835089D01*
G01X138810Y-841339D02*
X139443Y-840505D01*
X139760Y-839672D01*
Y-836339D01*
X139443Y-835505D01*
X138810Y-834672D01*
G01X142200Y-838672D02*
X142580Y-839255D01*
X143086Y-839589D01*
X143656Y-839672D01*
X144163Y-839589D01*
X144670Y-839172D01*
X144986Y-838672D01*
X145050Y-838172D01*
X144923Y-837589D01*
X144480Y-837172D01*
X144036Y-837005D01*
X143466D01*
G01X144036D02*
X144416Y-836755D01*
X144733Y-836339D01*
X144860Y-835839D01*
X144733Y-835339D01*
X144416Y-834922D01*
X143846Y-834672D01*
X143276Y-834755D01*
X142706Y-835089D01*
G01X147616Y-839089D02*
X148060Y-839505D01*
X148566Y-839672D01*
X149073Y-839505D01*
X149516Y-839005D01*
X149833Y-838255D01*
X149960Y-837505D01*
Y-836589D01*
X149833Y-835839D01*
X149516Y-835172D01*
X149136Y-834839D01*
X148693Y-834672D01*
X148186Y-834839D01*
X147806Y-835172D01*
X147553Y-835672D01*
X147426Y-836339D01*
X147553Y-836922D01*
X147870Y-837505D01*
X148250Y-837839D01*
X148693Y-837922D01*
X149200Y-837755D01*
X149580Y-837339D01*
X149960Y-836589D01*
G01X153666Y-839672D02*
X153793Y-838589D01*
X153983Y-837672D01*
X154236Y-836839D01*
X154553Y-835922D01*
X155060Y-834672D01*
X152526D01*
G01X158070Y-838005D02*
X159716D01*
G01X162600Y-838672D02*
X162980Y-839255D01*
X163486Y-839589D01*
X164056Y-839672D01*
X164563Y-839589D01*
X165070Y-839172D01*
X165386Y-838672D01*
X165450Y-838172D01*
X165323Y-837589D01*
X164880Y-837172D01*
X164436Y-837005D01*
X163866D01*
G01X164436D02*
X164816Y-836755D01*
X165133Y-836339D01*
X165260Y-835839D01*
X165133Y-835339D01*
X164816Y-834922D01*
X164246Y-834672D01*
X163676Y-834755D01*
X163106Y-835089D01*
G01X167890Y-837589D02*
X168333Y-837005D01*
X168713Y-836672D01*
X169220Y-836505D01*
X169663Y-836672D01*
X169980Y-837005D01*
X170233Y-837505D01*
X170296Y-838089D01*
X170233Y-838589D01*
X169980Y-839089D01*
X169600Y-839505D01*
X169156Y-839672D01*
X168650Y-839505D01*
X168206Y-839005D01*
X167953Y-838255D01*
X167890Y-837422D01*
X168016Y-836339D01*
X168206Y-835755D01*
X168523Y-835172D01*
X168966Y-834755D01*
X169410Y-834672D01*
X169853Y-834839D01*
X170170Y-835255D01*
G01X174193Y-839672D02*
Y-834672D01*
X173433Y-835672D01*
G01Y-839672D02*
X174953D01*
G01X180053D02*
Y-834672D01*
X177710Y-838255D01*
X180876D01*
G01X199093Y-769672D02*
Y-844672D01*
G01Y-819672D02*
X302093D01*
Y-794672D01*
G01X199093D02*
X302093D01*
G01X309600Y-829672D02*
Y-824672D01*
X310866D01*
X311373Y-824922D01*
X311753Y-825255D01*
X312070Y-825755D01*
X312323Y-826339D01*
X312386Y-827172D01*
X312323Y-828005D01*
X312070Y-828589D01*
X311753Y-829089D01*
X311373Y-829422D01*
X310866Y-829672D01*
X309600D01*
G01X314510D02*
X316093Y-824672D01*
X317676Y-829672D01*
G01X317106Y-827922D02*
X315080D01*
G01X321193Y-824672D02*
Y-829672D01*
G01X319736Y-824672D02*
X322650D01*
G01X327560Y-829672D02*
X325026D01*
Y-824672D01*
X327560D01*
G01X326546Y-827089D02*
X325026D01*
G01X331393Y-829839D02*
X331266Y-829755D01*
Y-829589D01*
X331393Y-829505D01*
X331520Y-829589D01*
Y-829755D01*
X331393Y-829839D01*
G01Y-827589D02*
X331266Y-827505D01*
Y-827339D01*
X331393Y-827255D01*
X331520Y-827339D01*
Y-827505D01*
X331393Y-827589D01*
G01X304093Y-769672D02*
Y-844672D01*
G01X302093Y-769672D02*
Y-844672D01*
G01X304093Y-819672D02*
X504093D01*
G01X309726Y-804672D02*
Y-799672D01*
X311246D01*
X311753Y-799922D01*
X312133Y-800505D01*
X312260Y-801172D01*
X312133Y-801839D01*
X311816Y-802339D01*
X311246Y-802589D01*
X309726D01*
G01X314953Y-804839D02*
X317233Y-799672D01*
G01X319736Y-804672D02*
Y-799672D01*
X322650Y-804672D01*
Y-799672D01*
G01X326293Y-804839D02*
X326166Y-804755D01*
Y-804589D01*
X326293Y-804505D01*
X326420Y-804589D01*
Y-804755D01*
X326293Y-804839D01*
G01Y-802589D02*
X326166Y-802505D01*
Y-802339D01*
X326293Y-802255D01*
X326420Y-802339D01*
Y-802505D01*
X326293Y-802589D01*
G01X304093Y-794672D02*
X504093D01*
G01X309726Y-779672D02*
Y-774672D01*
X311246D01*
X311753Y-774922D01*
X312133Y-775505D01*
X312260Y-776172D01*
X312133Y-776839D01*
X311816Y-777339D01*
X311246Y-777589D01*
X309726D01*
G01X314826Y-779672D02*
Y-774672D01*
X316410D01*
X316916Y-774922D01*
X317233Y-775255D01*
X317360Y-775922D01*
X317233Y-776589D01*
X316853Y-777005D01*
X316410Y-777255D01*
X314826D01*
G01X316410D02*
X317360Y-779672D01*
G01X321193D02*
X320686Y-779589D01*
X320243Y-779255D01*
X319863Y-778755D01*
X319610Y-778172D01*
X319483Y-777505D01*
Y-776839D01*
X319610Y-776172D01*
X319863Y-775589D01*
X320243Y-775089D01*
X320686Y-774755D01*
X321193Y-774672D01*
X321700Y-774755D01*
X322143Y-775089D01*
X322523Y-775589D01*
X322776Y-776172D01*
X322903Y-776839D01*
Y-777505D01*
X322776Y-778172D01*
X322523Y-778755D01*
X322143Y-779255D01*
X321700Y-779589D01*
X321193Y-779672D01*
G01X325026Y-778672D02*
X325343Y-779172D01*
X325723Y-779505D01*
X326166Y-779672D01*
X326673Y-779505D01*
X327053Y-779172D01*
X327433Y-778672D01*
X327560Y-778005D01*
Y-774672D01*
G01X332660Y-779672D02*
X330126D01*
Y-774672D01*
X332660D01*
G01X331646Y-777089D02*
X330126D01*
G01X337886Y-775089D02*
X337506Y-774839D01*
X337063Y-774672D01*
X336556D01*
X335986Y-774922D01*
X335543Y-775339D01*
X335226Y-775839D01*
X334973Y-776672D01*
X334910Y-777422D01*
X335036Y-778172D01*
X335226Y-778672D01*
X335606Y-779172D01*
X336050Y-779505D01*
X336493Y-779672D01*
X336936D01*
X337380Y-779505D01*
X337760Y-779255D01*
X338076Y-778922D01*
G01X341593Y-774672D02*
Y-779672D01*
G01X340136Y-774672D02*
X343050D01*
G01X346693Y-779839D02*
X346566Y-779755D01*
Y-779589D01*
X346693Y-779505D01*
X346820Y-779589D01*
Y-779755D01*
X346693Y-779839D01*
G01Y-777589D02*
X346566Y-777505D01*
Y-777339D01*
X346693Y-777255D01*
X346820Y-777339D01*
Y-777505D01*
X346693Y-777589D01*
G01X419093Y-819672D02*
Y-844672D01*
G01X421726Y-822172D02*
Y-827172D01*
X424260D01*
G01X427333Y-822172D02*
X428853D01*
G01X428093D02*
Y-827172D01*
G01X427333D02*
X428853D01*
G01X433700Y-824505D02*
X433953Y-824255D01*
X434143Y-823839D01*
X434270Y-823255D01*
X434143Y-822755D01*
X433890Y-822422D01*
X433446Y-822172D01*
X431736D01*
Y-827172D01*
X433826D01*
X434270Y-826839D01*
X434523Y-826339D01*
X434650Y-825755D01*
X434523Y-825172D01*
X434143Y-824672D01*
X433700Y-824505D01*
X431736D01*
G01X438293Y-827339D02*
X438166Y-827255D01*
Y-827089D01*
X438293Y-827005D01*
X438420Y-827089D01*
Y-827255D01*
X438293Y-827339D01*
G01Y-825089D02*
X438166Y-825005D01*
Y-824839D01*
X438293Y-824755D01*
X438420Y-824839D01*
Y-825005D01*
X438293Y-825089D01*
G01X470106Y-847839D02*
X470213Y-847714D01*
X470293Y-847505D01*
X470346Y-847214D01*
X470293Y-846964D01*
X470186Y-846797D01*
X470000Y-846672D01*
X469280D01*
Y-849172D01*
X470160D01*
X470346Y-849005D01*
X470453Y-848755D01*
X470506Y-848464D01*
X470453Y-848172D01*
X470293Y-847922D01*
X470106Y-847839D01*
X469280D01*
G01X472573Y-849172D02*
Y-847505D01*
G01Y-847797D02*
X472466Y-847630D01*
X472306Y-847547D01*
X472120Y-847505D01*
X471933Y-847589D01*
X471773Y-847755D01*
X471666Y-848005D01*
X471613Y-848339D01*
X471666Y-848672D01*
X471773Y-848922D01*
X471933Y-849089D01*
X472120Y-849172D01*
X472306Y-849130D01*
X472466Y-849005D01*
X472573Y-848839D01*
G01X473893Y-848880D02*
X474026Y-849047D01*
X474213Y-849172D01*
X474373D01*
X474533Y-849089D01*
X474640Y-848964D01*
X474693Y-848797D01*
X474666Y-848547D01*
X474560Y-848422D01*
X474080Y-848172D01*
X473973Y-847880D01*
X474026Y-847672D01*
X474133Y-847547D01*
X474293Y-847505D01*
X474453Y-847547D01*
X474613Y-847672D01*
G01X476093Y-848047D02*
X476946D01*
X476866Y-847755D01*
X476733Y-847589D01*
X476546Y-847505D01*
X476360Y-847547D01*
X476200Y-847672D01*
X476093Y-847964D01*
X476040Y-848214D01*
Y-848464D01*
X476093Y-848714D01*
X476226Y-848964D01*
X476386Y-849130D01*
X476573Y-849172D01*
X476760Y-849089D01*
X476946Y-848839D01*
G01X478213Y-849172D02*
Y-846672D01*
G01Y-847922D02*
X478346Y-847672D01*
X478506Y-847547D01*
X478666Y-847505D01*
X478906Y-847589D01*
X479066Y-847755D01*
X479173Y-848047D01*
Y-848380D01*
X479120Y-848714D01*
X479013Y-848964D01*
X478826Y-849130D01*
X478666Y-849172D01*
X478506Y-849130D01*
X478346Y-849005D01*
X478213Y-848797D01*
G01X480893Y-849172D02*
X480733Y-849130D01*
X480573Y-848964D01*
X480466Y-848672D01*
X480413Y-848339D01*
X480466Y-848005D01*
X480573Y-847714D01*
X480733Y-847547D01*
X480893Y-847505D01*
X481053Y-847547D01*
X481213Y-847714D01*
X481320Y-848005D01*
X481346Y-848339D01*
X481320Y-848672D01*
X481213Y-848964D01*
X481053Y-849130D01*
X480893Y-849172D01*
G01X483573D02*
Y-847505D01*
G01Y-847797D02*
X483466Y-847630D01*
X483306Y-847547D01*
X483120Y-847505D01*
X482933Y-847589D01*
X482773Y-847755D01*
X482666Y-848005D01*
X482613Y-848339D01*
X482666Y-848672D01*
X482773Y-848922D01*
X482933Y-849089D01*
X483120Y-849172D01*
X483306Y-849130D01*
X483466Y-849005D01*
X483573Y-848839D01*
G01X484920Y-849172D02*
Y-847505D01*
G01Y-847839D02*
X485053Y-847672D01*
X485186Y-847547D01*
X485373Y-847505D01*
X485506Y-847547D01*
X485666Y-847672D01*
G01X487973Y-846672D02*
Y-849172D01*
G01Y-848797D02*
X487866Y-849005D01*
X487706Y-849130D01*
X487520Y-849172D01*
X487306Y-849089D01*
X487146Y-848880D01*
X487040Y-848630D01*
X487013Y-848339D01*
X487040Y-848047D01*
X487146Y-847797D01*
X487306Y-847589D01*
X487520Y-847505D01*
X487706Y-847547D01*
X487840Y-847630D01*
X487973Y-847797D01*
G01X491360Y-849172D02*
Y-846672D01*
X492026D01*
X492240Y-846797D01*
X492373Y-846964D01*
X492426Y-847297D01*
X492373Y-847630D01*
X492213Y-847839D01*
X492026Y-847964D01*
X491360D01*
G01X492026D02*
X492426Y-849172D01*
G01X493693Y-848047D02*
X494546D01*
X494466Y-847755D01*
X494333Y-847589D01*
X494146Y-847505D01*
X493960Y-847547D01*
X493800Y-847672D01*
X493693Y-847964D01*
X493640Y-848214D01*
Y-848464D01*
X493693Y-848714D01*
X493826Y-848964D01*
X493986Y-849130D01*
X494173Y-849172D01*
X494360Y-849089D01*
X494546Y-848839D01*
G01X495813Y-847505D02*
X496293Y-849172D01*
X496773Y-847505D01*
G01X498493Y-849255D02*
X498440Y-849214D01*
Y-849130D01*
X498493Y-849089D01*
X498546Y-849130D01*
Y-849214D01*
X498493Y-849255D01*
G01X500693Y-849172D02*
X500880Y-849130D01*
X501093Y-849005D01*
X501226Y-848797D01*
X501280Y-848505D01*
X501226Y-848214D01*
X501066Y-847964D01*
X500826Y-847839D01*
X500560D01*
X500400Y-847755D01*
X500266Y-847547D01*
X500213Y-847255D01*
X500293Y-846964D01*
X500480Y-846755D01*
X500693Y-846672D01*
X500906Y-846755D01*
X501093Y-846964D01*
X501173Y-847255D01*
X501120Y-847547D01*
X500986Y-847755D01*
X500826Y-847839D01*
X500560D01*
X500320Y-847964D01*
X500160Y-848214D01*
X500106Y-848505D01*
X500160Y-848797D01*
X500293Y-849005D01*
X500506Y-849130D01*
X500693Y-849172D01*
G01X503106Y-847839D02*
X503213Y-847714D01*
X503293Y-847505D01*
X503346Y-847214D01*
X503293Y-846964D01*
X503186Y-846797D01*
X503000Y-846672D01*
X502280D01*
Y-849172D01*
X503160D01*
X503346Y-849005D01*
X503453Y-848755D01*
X503506Y-848464D01*
X503453Y-848172D01*
X503293Y-847922D01*
X503106Y-847839D01*
X502280D01*
G01X465993Y-822172D02*
Y-827172D01*
G01X464536Y-822172D02*
X467450D01*
G01X471093Y-827172D02*
X470713Y-827089D01*
X470333Y-826755D01*
X470080Y-826172D01*
X469953Y-825505D01*
X470080Y-824839D01*
X470333Y-824255D01*
X470713Y-823922D01*
X471093Y-823839D01*
X471473Y-823922D01*
X471853Y-824255D01*
X472106Y-824839D01*
X472170Y-825505D01*
X472106Y-826172D01*
X471853Y-826755D01*
X471473Y-827089D01*
X471093Y-827172D01*
G01X476193D02*
X475813Y-827089D01*
X475433Y-826755D01*
X475180Y-826172D01*
X475053Y-825505D01*
X475180Y-824839D01*
X475433Y-824255D01*
X475813Y-823922D01*
X476193Y-823839D01*
X476573Y-823922D01*
X476953Y-824255D01*
X477206Y-824839D01*
X477270Y-825505D01*
X477206Y-826172D01*
X476953Y-826755D01*
X476573Y-827089D01*
X476193Y-827172D01*
G01X481293D02*
Y-822172D01*
G01X486393Y-827339D02*
X486266Y-827255D01*
Y-827089D01*
X486393Y-827005D01*
X486520Y-827089D01*
Y-827255D01*
X486393Y-827339D01*
G01Y-825089D02*
X486266Y-825005D01*
Y-824839D01*
X486393Y-824755D01*
X486520Y-824839D01*
Y-825005D01*
X486393Y-825089D01*
G01X462093Y-819672D02*
Y-844672D01*
G01Y-794672D02*
Y-819672D01*
G01X464726Y-802172D02*
Y-797172D01*
X466310D01*
X466816Y-797422D01*
X467133Y-797755D01*
X467260Y-798422D01*
X467133Y-799089D01*
X466753Y-799505D01*
X466310Y-799755D01*
X464726D01*
G01X466310D02*
X467260Y-802172D01*
G01X472360D02*
X469826D01*
Y-797172D01*
X472360D01*
G01X471346Y-799589D02*
X469826D01*
G01X474610Y-797172D02*
X476193Y-802172D01*
X477776Y-797172D01*
G01X481293Y-802339D02*
X481166Y-802255D01*
Y-802089D01*
X481293Y-802005D01*
X481420Y-802089D01*
Y-802255D01*
X481293Y-802339D01*
G01Y-800089D02*
X481166Y-800005D01*
Y-799839D01*
X481293Y-799755D01*
X481420Y-799839D01*
Y-800005D01*
X481293Y-800089D01*
G01X-297025Y-1013390D02*
Y1828909D01*
X3691357D01*
Y-1013390D01*
X-297025D01*
G01X16913Y-817022D02*
X18480D01*
Y-818912D01*
X18010Y-819542D01*
X17461Y-819962D01*
X16678Y-820172D01*
X15895Y-819962D01*
X15346Y-819542D01*
X14876Y-818912D01*
X14563Y-818177D01*
X14406Y-817337D01*
Y-816602D01*
X14563Y-815972D01*
X14876Y-815237D01*
X15346Y-814607D01*
X15816Y-814187D01*
X16443Y-813872D01*
X16991D01*
X17618Y-814082D01*
X18088Y-814502D01*
G01X21020Y-813872D02*
Y-818387D01*
X21333Y-819332D01*
X21960Y-819962D01*
X22743Y-820172D01*
X23526Y-819962D01*
X24153Y-819332D01*
X24466Y-818387D01*
Y-813872D01*
G01X28103D02*
X29983D01*
G01X29043D02*
Y-820172D01*
G01X28103D02*
X29983D01*
G01X33698Y-819332D02*
X34325Y-819857D01*
X35030Y-820172D01*
X35656D01*
X36283Y-819857D01*
X36753Y-819332D01*
X36988Y-818597D01*
X36831Y-817862D01*
X36440Y-817232D01*
X35735Y-816812D01*
X34795Y-816602D01*
X34246Y-816182D01*
X34011Y-815447D01*
X34168Y-814712D01*
X34560Y-814187D01*
X35108Y-813872D01*
X35656D01*
X36205Y-814082D01*
X36675Y-814607D01*
G01X39998Y-820172D02*
Y-813872D01*
G01X43288D02*
Y-820172D01*
G01Y-817022D02*
X39998D01*
G01X45985Y-820172D02*
X47943Y-813872D01*
X49901Y-820172D01*
G01X49196Y-817967D02*
X46690D01*
G01X52441Y-820172D02*
Y-813872D01*
X56045Y-820172D01*
Y-813872D01*
G01X65120Y-820172D02*
Y-813872D01*
X66686D01*
X67313Y-814187D01*
X67783Y-814607D01*
X68175Y-815237D01*
X68488Y-815972D01*
X68566Y-817022D01*
X68488Y-818072D01*
X68175Y-818807D01*
X67783Y-819437D01*
X67313Y-819857D01*
X66686Y-820172D01*
X65120D01*
G01X72203Y-813872D02*
X74083D01*
G01X73143D02*
Y-820172D01*
G01X72203D02*
X74083D01*
G01X77798Y-819332D02*
X78425Y-819857D01*
X79130Y-820172D01*
X79756D01*
X80383Y-819857D01*
X80853Y-819332D01*
X81088Y-818597D01*
X80931Y-817862D01*
X80540Y-817232D01*
X79835Y-816812D01*
X78895Y-816602D01*
X78346Y-816182D01*
X78111Y-815447D01*
X78268Y-814712D01*
X78660Y-814187D01*
X79208Y-813872D01*
X79756D01*
X80305Y-814082D01*
X80775Y-814607D01*
G01X85743Y-813872D02*
Y-820172D01*
G01X83941Y-813872D02*
X87545D01*
G01X92043Y-820382D02*
X91886Y-820277D01*
Y-820067D01*
X92043Y-819962D01*
X92200Y-820067D01*
Y-820277D01*
X92043Y-820382D01*
G01X98186Y-821327D02*
X98500Y-819962D01*
G01X104643Y-813872D02*
Y-820172D01*
G01X102841Y-813872D02*
X106445D01*
G01X108985Y-820172D02*
X110943Y-813872D01*
X112901Y-820172D01*
G01X112196Y-817967D02*
X109690D01*
G01X117243Y-820172D02*
X116616Y-820067D01*
X116068Y-819647D01*
X115598Y-819017D01*
X115285Y-818282D01*
X115128Y-817442D01*
Y-816602D01*
X115285Y-815762D01*
X115598Y-815027D01*
X116068Y-814397D01*
X116616Y-813977D01*
X117243Y-813872D01*
X117870Y-813977D01*
X118418Y-814397D01*
X118888Y-815027D01*
X119201Y-815762D01*
X119358Y-816602D01*
Y-817442D01*
X119201Y-818282D01*
X118888Y-819017D01*
X118418Y-819647D01*
X117870Y-820067D01*
X117243Y-820172D01*
G01X123543D02*
Y-817337D01*
X121976Y-813872D01*
G01X125110D02*
X123543Y-817337D01*
G01X128120Y-813872D02*
Y-818387D01*
X128433Y-819332D01*
X129060Y-819962D01*
X129843Y-820172D01*
X130626Y-819962D01*
X131253Y-819332D01*
X131566Y-818387D01*
Y-813872D01*
G01X134185Y-820172D02*
X136143Y-813872D01*
X138101Y-820172D01*
G01X137396Y-817967D02*
X134890D01*
G01X140641Y-820172D02*
Y-813872D01*
X144245Y-820172D01*
Y-813872D01*
G01X18166Y-824397D02*
X17696Y-824082D01*
X17148Y-823872D01*
X16521D01*
X15816Y-824187D01*
X15268Y-824712D01*
X14876Y-825342D01*
X14563Y-826392D01*
X14485Y-827337D01*
X14641Y-828282D01*
X14876Y-828912D01*
X15346Y-829542D01*
X15895Y-829962D01*
X16443Y-830172D01*
X16991D01*
X17540Y-829962D01*
X18010Y-829647D01*
X18401Y-829227D01*
G01X21803Y-823872D02*
X23683D01*
G01X22743D02*
Y-830172D01*
G01X21803D02*
X23683D01*
G01X29043Y-823872D02*
Y-830172D01*
G01X27241Y-823872D02*
X30845D01*
G01X35343Y-830172D02*
Y-827337D01*
X33776Y-823872D01*
G01X36910D02*
X35343Y-827337D01*
G01X46220Y-828912D02*
X46690Y-829647D01*
X47316Y-830067D01*
X48021Y-830172D01*
X48648Y-830067D01*
X49275Y-829542D01*
X49666Y-828912D01*
X49745Y-828282D01*
X49588Y-827547D01*
X49040Y-827022D01*
X48491Y-826812D01*
X47786D01*
G01X48491D02*
X48961Y-826497D01*
X49353Y-825972D01*
X49510Y-825342D01*
X49353Y-824712D01*
X48961Y-824187D01*
X48256Y-823872D01*
X47551Y-823977D01*
X46846Y-824397D01*
G01X52520Y-828912D02*
X52990Y-829647D01*
X53616Y-830067D01*
X54321Y-830172D01*
X54948Y-830067D01*
X55575Y-829542D01*
X55966Y-828912D01*
X56045Y-828282D01*
X55888Y-827547D01*
X55340Y-827022D01*
X54791Y-826812D01*
X54086D01*
G01X54791D02*
X55261Y-826497D01*
X55653Y-825972D01*
X55810Y-825342D01*
X55653Y-824712D01*
X55261Y-824187D01*
X54556Y-823872D01*
X53851Y-823977D01*
X53146Y-824397D01*
G01X58820Y-828912D02*
X59290Y-829647D01*
X59916Y-830067D01*
X60621Y-830172D01*
X61248Y-830067D01*
X61875Y-829542D01*
X62266Y-828912D01*
X62345Y-828282D01*
X62188Y-827547D01*
X61640Y-827022D01*
X61091Y-826812D01*
X60386D01*
G01X61091D02*
X61561Y-826497D01*
X61953Y-825972D01*
X62110Y-825342D01*
X61953Y-824712D01*
X61561Y-824187D01*
X60856Y-823872D01*
X60151Y-823977D01*
X59446Y-824397D01*
G01X66686Y-830172D02*
X66843Y-828807D01*
X67078Y-827652D01*
X67391Y-826602D01*
X67783Y-825447D01*
X68410Y-823872D01*
X65276D01*
G01X72986Y-830172D02*
X73143Y-828807D01*
X73378Y-827652D01*
X73691Y-826602D01*
X74083Y-825447D01*
X74710Y-823872D01*
X71576D01*
G01X79286Y-831327D02*
X79600Y-829962D01*
G01X85743Y-823872D02*
Y-830172D01*
G01X83941Y-823872D02*
X87545D01*
G01X90085Y-830172D02*
X92043Y-823872D01*
X94001Y-830172D01*
G01X93296Y-827967D02*
X90790D01*
G01X97403Y-823872D02*
X99283D01*
G01X98343D02*
Y-830172D01*
G01X97403D02*
X99283D01*
G01X102293Y-823872D02*
X103390Y-830172D01*
X104643Y-823872D01*
X105896Y-830172D01*
X106993Y-823872D01*
G01X108985Y-830172D02*
X110943Y-823872D01*
X112901Y-830172D01*
G01X112196Y-827967D02*
X109690D01*
G01X115441Y-830172D02*
Y-823872D01*
X119045Y-830172D01*
Y-823872D01*
G01X129451Y-832272D02*
X128668Y-831222D01*
X128276Y-830172D01*
Y-825972D01*
X128668Y-824922D01*
X129451Y-823872D01*
G01X140876Y-830172D02*
Y-823872D01*
X142835D01*
X143461Y-824187D01*
X143853Y-824607D01*
X144010Y-825447D01*
X143853Y-826287D01*
X143383Y-826812D01*
X142835Y-827127D01*
X140876D01*
G01X142835D02*
X144010Y-830172D01*
G01X148743Y-830382D02*
X148586Y-830277D01*
Y-830067D01*
X148743Y-829962D01*
X148900Y-830067D01*
Y-830277D01*
X148743Y-830382D01*
G01X155043Y-830172D02*
X154416Y-830067D01*
X153868Y-829647D01*
X153398Y-829017D01*
X153085Y-828282D01*
X152928Y-827442D01*
Y-826602D01*
X153085Y-825762D01*
X153398Y-825027D01*
X153868Y-824397D01*
X154416Y-823977D01*
X155043Y-823872D01*
X155670Y-823977D01*
X156218Y-824397D01*
X156688Y-825027D01*
X157001Y-825762D01*
X157158Y-826602D01*
Y-827442D01*
X157001Y-828282D01*
X156688Y-829017D01*
X156218Y-829647D01*
X155670Y-830067D01*
X155043Y-830172D01*
G01X161343Y-830382D02*
X161186Y-830277D01*
Y-830067D01*
X161343Y-829962D01*
X161500Y-830067D01*
Y-830277D01*
X161343Y-830382D01*
G01X169366Y-824397D02*
X168896Y-824082D01*
X168348Y-823872D01*
X167721D01*
X167016Y-824187D01*
X166468Y-824712D01*
X166076Y-825342D01*
X165763Y-826392D01*
X165685Y-827337D01*
X165841Y-828282D01*
X166076Y-828912D01*
X166546Y-829542D01*
X167095Y-829962D01*
X167643Y-830172D01*
X168191D01*
X168740Y-829962D01*
X169210Y-829647D01*
X169601Y-829227D01*
G01X173943Y-830382D02*
X173786Y-830277D01*
Y-830067D01*
X173943Y-829962D01*
X174100Y-830067D01*
Y-830277D01*
X173943Y-830382D01*
G01X180635Y-832272D02*
X181418Y-831222D01*
X181810Y-830172D01*
Y-825972D01*
X181418Y-824922D01*
X180635Y-823872D01*
G01X38743Y-799472D02*
X36223Y-799055D01*
X34018Y-797389D01*
X32128Y-794889D01*
X30868Y-791972D01*
X30238Y-788639D01*
Y-785305D01*
X30868Y-781972D01*
X32128Y-779055D01*
X34018Y-776556D01*
X36223Y-774889D01*
X38743Y-774472D01*
X41263Y-774889D01*
X43468Y-776556D01*
X45358Y-779055D01*
X46618Y-781972D01*
X47248Y-785305D01*
Y-788639D01*
X46618Y-791972D01*
X45358Y-794889D01*
X43468Y-797389D01*
X41263Y-799055D01*
X38743Y-799472D01*
G01X41263Y-792805D02*
X45043Y-799472D01*
G01X58588Y-782806D02*
Y-794472D01*
X59848Y-797389D01*
X61738Y-799055D01*
X63943Y-799472D01*
X66148Y-799055D01*
X68038Y-797389D01*
X69298Y-794472D01*
G01Y-799472D02*
Y-782806D01*
G01X94813Y-799472D02*
Y-782806D01*
G01Y-785722D02*
X93553Y-784056D01*
X91663Y-783222D01*
X89458Y-782806D01*
X87253Y-783639D01*
X85363Y-785305D01*
X84103Y-787806D01*
X83473Y-791139D01*
X84103Y-794472D01*
X85363Y-796973D01*
X87253Y-798639D01*
X89458Y-799472D01*
X91663Y-799055D01*
X93553Y-797806D01*
X94813Y-796139D01*
G01X108988Y-799472D02*
Y-782806D01*
G01Y-786972D02*
X110248Y-784889D01*
X112138Y-783222D01*
X114658Y-782806D01*
X116863Y-783222D01*
X118753Y-784889D01*
X119698Y-787806D01*
Y-799472D01*
G01X139543Y-774472D02*
Y-799472D01*
G01X135133Y-782806D02*
X143953D01*
G01X170413Y-799472D02*
Y-782806D01*
G01Y-785722D02*
X169153Y-784056D01*
X167263Y-783222D01*
X165058Y-782806D01*
X162853Y-783639D01*
X160963Y-785305D01*
X159703Y-787806D01*
X159073Y-791139D01*
X159703Y-794472D01*
X160963Y-796973D01*
X162853Y-798639D01*
X165058Y-799472D01*
X167263Y-799055D01*
X169153Y-797806D01*
X170413Y-796139D01*
G01X14641Y-810172D02*
Y-803872D01*
X18245Y-810172D01*
Y-803872D01*
G01X22743Y-810172D02*
X22116Y-810067D01*
X21568Y-809647D01*
X21098Y-809017D01*
X20785Y-808282D01*
X20628Y-807442D01*
Y-806602D01*
X20785Y-805762D01*
X21098Y-805027D01*
X21568Y-804397D01*
X22116Y-803977D01*
X22743Y-803872D01*
X23370Y-803977D01*
X23918Y-804397D01*
X24388Y-805027D01*
X24701Y-805762D01*
X24858Y-806602D01*
Y-807442D01*
X24701Y-808282D01*
X24388Y-809017D01*
X23918Y-809647D01*
X23370Y-810067D01*
X22743Y-810172D01*
G01X29043Y-810382D02*
X28886Y-810277D01*
Y-810067D01*
X29043Y-809962D01*
X29200Y-810067D01*
Y-810277D01*
X29043Y-810382D01*
G01X33855Y-804922D02*
X34325Y-804292D01*
X34873Y-803977D01*
X35500Y-803872D01*
X36283Y-804082D01*
X36831Y-804607D01*
X36988Y-805237D01*
X36910Y-805867D01*
X36596Y-806392D01*
X35030Y-807442D01*
X34325Y-808177D01*
X33855Y-809227D01*
X33698Y-810172D01*
X36988D01*
G01X41643D02*
Y-803872D01*
X40703Y-805132D01*
G01Y-810172D02*
X42583D01*
G01X47943D02*
Y-803872D01*
X47003Y-805132D01*
G01Y-810172D02*
X48883D01*
G01X54086Y-811327D02*
X54400Y-809962D01*
G01X58193Y-803872D02*
X59290Y-810172D01*
X60543Y-803872D01*
X61796Y-810172D01*
X62893Y-803872D01*
G01X68410Y-810172D02*
X65276D01*
Y-803872D01*
X68410D01*
G01X67156Y-806917D02*
X65276D01*
G01X71341Y-810172D02*
Y-803872D01*
X74945Y-810172D01*
Y-803872D01*
G01X77798Y-810172D02*
Y-803872D01*
G01X81088D02*
Y-810172D01*
G01Y-807022D02*
X77798D01*
G01X84020Y-803872D02*
Y-808387D01*
X84333Y-809332D01*
X84960Y-809962D01*
X85743Y-810172D01*
X86526Y-809962D01*
X87153Y-809332D01*
X87466Y-808387D01*
Y-803872D01*
G01X90085Y-810172D02*
X92043Y-803872D01*
X94001Y-810172D01*
G01X93296Y-807967D02*
X90790D01*
G01X103155Y-804922D02*
X103625Y-804292D01*
X104173Y-803977D01*
X104800Y-803872D01*
X105583Y-804082D01*
X106131Y-804607D01*
X106288Y-805237D01*
X106210Y-805867D01*
X105896Y-806392D01*
X104330Y-807442D01*
X103625Y-808177D01*
X103155Y-809227D01*
X102998Y-810172D01*
X106288D01*
G01X109141D02*
Y-803872D01*
X112745Y-810172D01*
Y-803872D01*
G01X115520Y-810172D02*
Y-803872D01*
X117086D01*
X117713Y-804187D01*
X118183Y-804607D01*
X118575Y-805237D01*
X118888Y-805972D01*
X118966Y-807022D01*
X118888Y-808072D01*
X118575Y-808807D01*
X118183Y-809437D01*
X117713Y-809857D01*
X117086Y-810172D01*
X115520D01*
G01X128276D02*
Y-803872D01*
X130235D01*
X130861Y-804187D01*
X131253Y-804607D01*
X131410Y-805447D01*
X131253Y-806287D01*
X130783Y-806812D01*
X130235Y-807127D01*
X128276D01*
G01X130235D02*
X131410Y-810172D01*
G01X134420D02*
Y-803872D01*
X135986D01*
X136613Y-804187D01*
X137083Y-804607D01*
X137475Y-805237D01*
X137788Y-805972D01*
X137866Y-807022D01*
X137788Y-808072D01*
X137475Y-808807D01*
X137083Y-809437D01*
X136613Y-809857D01*
X135986Y-810172D01*
X134420D01*
G01X142443Y-810382D02*
X142286Y-810277D01*
Y-810067D01*
X142443Y-809962D01*
X142600Y-810067D01*
Y-810277D01*
X142443Y-810382D01*
G01X210093Y-779172D02*
Y-787172D01*
X214093D01*
G01X221893D02*
Y-781839D01*
G01Y-782772D02*
X221493Y-782239D01*
X220893Y-781972D01*
X220193Y-781839D01*
X219493Y-782105D01*
X218893Y-782639D01*
X218493Y-783439D01*
X218293Y-784505D01*
X218493Y-785572D01*
X218893Y-786372D01*
X219493Y-786905D01*
X220193Y-787172D01*
X220893Y-787039D01*
X221493Y-786639D01*
X221893Y-786106D01*
G01X225993Y-789572D02*
X226593Y-789839D01*
X227393Y-789572D01*
X227893Y-789039D01*
X228293Y-788372D01*
X228893Y-786239D01*
X230193Y-781839D01*
G01X226993D02*
X228893Y-786239D01*
G01X234593Y-783572D02*
X237793D01*
X237493Y-782639D01*
X236993Y-782105D01*
X236293Y-781839D01*
X235593Y-781972D01*
X234993Y-782372D01*
X234593Y-783305D01*
X234393Y-784106D01*
Y-784905D01*
X234593Y-785705D01*
X235093Y-786505D01*
X235693Y-787039D01*
X236393Y-787172D01*
X237093Y-786905D01*
X237793Y-786106D01*
G01X242693Y-787172D02*
Y-781839D01*
G01Y-782905D02*
X243193Y-782372D01*
X243693Y-781972D01*
X244393Y-781839D01*
X244893Y-781972D01*
X245493Y-782372D01*
G01X229193Y-829172D02*
X232993D01*
X229193Y-837172D01*
X232993D01*
G01X239093Y-831839D02*
Y-837172D01*
G01Y-829705D02*
X238893Y-829572D01*
Y-829305D01*
X239093Y-829172D01*
X239293Y-829305D01*
Y-829572D01*
X239093Y-829705D01*
G01X245793Y-834505D02*
X248393D01*
G01X253093Y-837172D02*
Y-829172D01*
X255493D01*
X256293Y-829572D01*
X256893Y-830505D01*
X257093Y-831572D01*
X256893Y-832639D01*
X256393Y-833439D01*
X255493Y-833839D01*
X253093D01*
G01X263093Y-831839D02*
Y-837172D01*
G01Y-829705D02*
X262893Y-829572D01*
Y-829305D01*
X263093Y-829172D01*
X263293Y-829305D01*
Y-829572D01*
X263093Y-829705D01*
G01X269393Y-837172D02*
Y-831839D01*
G01Y-833172D02*
X269793Y-832505D01*
X270393Y-831972D01*
X271193Y-831839D01*
X271893Y-831972D01*
X272493Y-832505D01*
X272793Y-833439D01*
Y-837172D01*
G01X277693Y-839172D02*
X278393Y-839705D01*
X279193Y-839839D01*
X279893Y-839705D01*
X280493Y-839039D01*
X280893Y-838105D01*
Y-831839D01*
G01Y-832905D02*
X280493Y-832372D01*
X279893Y-831972D01*
X279193Y-831839D01*
X278393Y-832105D01*
X277893Y-832639D01*
X277493Y-833572D01*
X277293Y-834505D01*
X277393Y-835305D01*
X277793Y-836239D01*
X278393Y-836905D01*
X279193Y-837172D01*
X279793Y-837039D01*
X280493Y-836505D01*
X280893Y-835972D01*
G01X241693Y-808172D02*
X243693D01*
Y-810572D01*
X243093Y-811372D01*
X242393Y-811905D01*
X241393Y-812172D01*
X240393Y-811905D01*
X239693Y-811372D01*
X239093Y-810572D01*
X238693Y-809639D01*
X238493Y-808572D01*
Y-807639D01*
X238693Y-806839D01*
X239093Y-805905D01*
X239693Y-805105D01*
X240293Y-804572D01*
X241093Y-804172D01*
X241793D01*
X242593Y-804439D01*
X243193Y-804972D01*
G01X246793Y-812172D02*
Y-804172D01*
X251393Y-812172D01*
Y-804172D01*
G01X254893Y-812172D02*
Y-804172D01*
X256893D01*
X257693Y-804572D01*
X258293Y-805105D01*
X258793Y-805905D01*
X259193Y-806839D01*
X259293Y-808172D01*
X259193Y-809505D01*
X258793Y-810439D01*
X258293Y-811239D01*
X257693Y-811772D01*
X256893Y-812172D01*
X254893D01*
G01X262893Y-810572D02*
X263493Y-811505D01*
X264293Y-812039D01*
X265193Y-812172D01*
X265993Y-812039D01*
X266793Y-811372D01*
X267293Y-810572D01*
X267393Y-809772D01*
X267193Y-808839D01*
X266493Y-808172D01*
X265793Y-807905D01*
X264893D01*
G01X265793D02*
X266393Y-807505D01*
X266893Y-806839D01*
X267093Y-806039D01*
X266893Y-805239D01*
X266393Y-804572D01*
X265493Y-804172D01*
X264593Y-804305D01*
X263693Y-804839D01*
G01X261893Y-786239D02*
X262593Y-786905D01*
X263393Y-787172D01*
X264193Y-786905D01*
X264893Y-786106D01*
X265393Y-784905D01*
X265593Y-783705D01*
Y-782239D01*
X265393Y-781039D01*
X264893Y-779972D01*
X264293Y-779439D01*
X263593Y-779172D01*
X262793Y-779439D01*
X262193Y-779972D01*
X261793Y-780772D01*
X261593Y-781839D01*
X261793Y-782772D01*
X262293Y-783705D01*
X262893Y-784239D01*
X263593Y-784372D01*
X264393Y-784106D01*
X264993Y-783439D01*
X265593Y-782239D01*
G01X336693Y-830505D02*
X337293Y-829705D01*
X337993Y-829305D01*
X338793Y-829172D01*
X339793Y-829439D01*
X340493Y-830105D01*
X340693Y-830905D01*
X340593Y-831706D01*
X340193Y-832372D01*
X338193Y-833705D01*
X337293Y-834639D01*
X336693Y-835972D01*
X336493Y-837172D01*
X340693D01*
G01X346593Y-829172D02*
X345793Y-829439D01*
X345193Y-830105D01*
X344793Y-830905D01*
X344493Y-831972D01*
X344393Y-833172D01*
X344493Y-834372D01*
X344793Y-835439D01*
X345193Y-836239D01*
X345793Y-836905D01*
X346593Y-837172D01*
X347393Y-836905D01*
X347993Y-836239D01*
X348393Y-835439D01*
X348693Y-834372D01*
X348793Y-833172D01*
X348693Y-831972D01*
X348393Y-830905D01*
X347993Y-830105D01*
X347393Y-829439D01*
X346593Y-829172D01*
G01X352693Y-830505D02*
X353293Y-829705D01*
X353993Y-829305D01*
X354793Y-829172D01*
X355793Y-829439D01*
X356493Y-830105D01*
X356693Y-830905D01*
X356593Y-831706D01*
X356193Y-832372D01*
X354193Y-833705D01*
X353293Y-834639D01*
X352693Y-835972D01*
X352493Y-837172D01*
X356693D01*
G01X360693Y-830505D02*
X361293Y-829705D01*
X361993Y-829305D01*
X362793Y-829172D01*
X363793Y-829439D01*
X364493Y-830105D01*
X364693Y-830905D01*
X364593Y-831706D01*
X364193Y-832372D01*
X362193Y-833705D01*
X361293Y-834639D01*
X360693Y-835972D01*
X360493Y-837172D01*
X364693D01*
G01X368793Y-837439D02*
X372393Y-829172D01*
G01X378593Y-837172D02*
Y-829172D01*
X377393Y-830772D01*
G01Y-837172D02*
X379793D01*
G01X384693Y-830505D02*
X385293Y-829705D01*
X385993Y-829305D01*
X386793Y-829172D01*
X387793Y-829439D01*
X388493Y-830105D01*
X388693Y-830905D01*
X388593Y-831706D01*
X388193Y-832372D01*
X386193Y-833705D01*
X385293Y-834639D01*
X384693Y-835972D01*
X384493Y-837172D01*
X388693D01*
G01X392793Y-837439D02*
X396393Y-829172D01*
G01X402593D02*
X401793Y-829439D01*
X401193Y-830105D01*
X400793Y-830905D01*
X400493Y-831972D01*
X400393Y-833172D01*
X400493Y-834372D01*
X400793Y-835439D01*
X401193Y-836239D01*
X401793Y-836905D01*
X402593Y-837172D01*
X403393Y-836905D01*
X403993Y-836239D01*
X404393Y-835439D01*
X404693Y-834372D01*
X404793Y-833172D01*
X404693Y-831972D01*
X404393Y-830905D01*
X403993Y-830105D01*
X403393Y-829439D01*
X402593Y-829172D01*
G01X408693Y-830505D02*
X409293Y-829705D01*
X409993Y-829305D01*
X410793Y-829172D01*
X411793Y-829439D01*
X412493Y-830105D01*
X412693Y-830905D01*
X412593Y-831706D01*
X412193Y-832372D01*
X410193Y-833705D01*
X409293Y-834639D01*
X408693Y-835972D01*
X408493Y-837172D01*
X412693D01*
G01X336393Y-814672D02*
Y-806672D01*
X338393D01*
X339193Y-807072D01*
X339793Y-807605D01*
X340293Y-808405D01*
X340693Y-809339D01*
X340793Y-810672D01*
X340693Y-812005D01*
X340293Y-812939D01*
X339793Y-813739D01*
X339193Y-814272D01*
X338393Y-814672D01*
X336393D01*
G01X344093D02*
X346593Y-806672D01*
X349093Y-814672D01*
G01X348193Y-811872D02*
X344993D01*
G01X354593Y-806672D02*
X353793Y-806939D01*
X353193Y-807605D01*
X352793Y-808405D01*
X352493Y-809472D01*
X352393Y-810672D01*
X352493Y-811872D01*
X352793Y-812939D01*
X353193Y-813739D01*
X353793Y-814405D01*
X354593Y-814672D01*
X355393Y-814405D01*
X355993Y-813739D01*
X356393Y-812939D01*
X356693Y-811872D01*
X356793Y-810672D01*
X356693Y-809472D01*
X356393Y-808405D01*
X355993Y-807605D01*
X355393Y-806939D01*
X354593Y-806672D01*
G01X360693Y-814672D02*
Y-806672D01*
X364493D01*
G01X363093Y-810539D02*
X360693D01*
G01X370593Y-806672D02*
X369793Y-806939D01*
X369193Y-807605D01*
X368793Y-808405D01*
X368493Y-809472D01*
X368393Y-810672D01*
X368493Y-811872D01*
X368793Y-812939D01*
X369193Y-813739D01*
X369793Y-814405D01*
X370593Y-814672D01*
X371393Y-814405D01*
X371993Y-813739D01*
X372393Y-812939D01*
X372693Y-811872D01*
X372793Y-810672D01*
X372693Y-809472D01*
X372393Y-808405D01*
X371993Y-807605D01*
X371393Y-806939D01*
X370593Y-806672D01*
G01X378593D02*
Y-814672D01*
G01X376293Y-806672D02*
X380893D01*
G01X384593Y-814672D02*
Y-806672D01*
X386993D01*
X387793Y-807072D01*
X388393Y-808005D01*
X388593Y-809072D01*
X388393Y-810139D01*
X387893Y-810939D01*
X386993Y-811339D01*
X384593D01*
G01X395393Y-810405D02*
X395793Y-810005D01*
X396093Y-809339D01*
X396293Y-808405D01*
X396093Y-807605D01*
X395693Y-807072D01*
X394993Y-806672D01*
X392293D01*
Y-814672D01*
X395593D01*
X396293Y-814139D01*
X396693Y-813339D01*
X396893Y-812405D01*
X396693Y-811472D01*
X396093Y-810672D01*
X395393Y-810405D01*
X392293D01*
G01X400093Y-814672D02*
X402593Y-806672D01*
X405093Y-814672D01*
G01X404193Y-811872D02*
X400993D01*
G01X408693Y-814672D02*
Y-806672D01*
X412493D01*
G01X411093Y-810539D02*
X408693D01*
G01X418593Y-806672D02*
X417793Y-806939D01*
X417193Y-807605D01*
X416793Y-808405D01*
X416493Y-809472D01*
X416393Y-810672D01*
X416493Y-811872D01*
X416793Y-812939D01*
X417193Y-813739D01*
X417793Y-814405D01*
X418593Y-814672D01*
X419393Y-814405D01*
X419993Y-813739D01*
X420393Y-812939D01*
X420693Y-811872D01*
X420793Y-810672D01*
X420693Y-809472D01*
X420393Y-808405D01*
X419993Y-807605D01*
X419393Y-806939D01*
X418593Y-806672D01*
G01X356693Y-787172D02*
Y-779172D01*
X360493D01*
G01X359093Y-783039D02*
X356693D01*
G01X366593Y-779172D02*
X365793Y-779439D01*
X365193Y-780105D01*
X364793Y-780905D01*
X364493Y-781972D01*
X364393Y-783172D01*
X364493Y-784372D01*
X364793Y-785439D01*
X365193Y-786239D01*
X365793Y-786905D01*
X366593Y-787172D01*
X367393Y-786905D01*
X367993Y-786239D01*
X368393Y-785439D01*
X368693Y-784372D01*
X368793Y-783172D01*
X368693Y-781972D01*
X368393Y-780905D01*
X367993Y-780105D01*
X367393Y-779439D01*
X366593Y-779172D01*
G01X374593D02*
Y-787172D01*
G01X372293Y-779172D02*
X376893D01*
G01X379593Y-789839D02*
X385593D01*
G01X388593Y-787172D02*
Y-779172D01*
X390993D01*
X391793Y-779572D01*
X392393Y-780505D01*
X392593Y-781572D01*
X392393Y-782639D01*
X391893Y-783439D01*
X390993Y-783839D01*
X388593D01*
G01X396393Y-787172D02*
Y-779172D01*
X398393D01*
X399193Y-779572D01*
X399793Y-780105D01*
X400293Y-780905D01*
X400693Y-781839D01*
X400793Y-783172D01*
X400693Y-784505D01*
X400293Y-785439D01*
X399793Y-786239D01*
X399193Y-786772D01*
X398393Y-787172D01*
X396393D01*
G01X407393Y-782905D02*
X407793Y-782505D01*
X408093Y-781839D01*
X408293Y-780905D01*
X408093Y-780105D01*
X407693Y-779572D01*
X406993Y-779172D01*
X404293D01*
Y-787172D01*
X407593D01*
X408293Y-786639D01*
X408693Y-785839D01*
X408893Y-784905D01*
X408693Y-783972D01*
X408093Y-783172D01*
X407393Y-782905D01*
X404293D01*
G01X411593Y-789839D02*
X417593D01*
G01X424793Y-779839D02*
X424193Y-779439D01*
X423493Y-779172D01*
X422693D01*
X421793Y-779572D01*
X421093Y-780239D01*
X420593Y-781039D01*
X420193Y-782372D01*
X420093Y-783572D01*
X420293Y-784772D01*
X420593Y-785572D01*
X421193Y-786372D01*
X421893Y-786905D01*
X422593Y-787172D01*
X423293D01*
X423993Y-786905D01*
X424593Y-786505D01*
X425093Y-785972D01*
G01X430593Y-787172D02*
X429793Y-787039D01*
X429093Y-786505D01*
X428493Y-785705D01*
X428093Y-784772D01*
X427893Y-783705D01*
Y-782639D01*
X428093Y-781572D01*
X428493Y-780639D01*
X429093Y-779839D01*
X429793Y-779305D01*
X430593Y-779172D01*
X431393Y-779305D01*
X432093Y-779839D01*
X432693Y-780639D01*
X433093Y-781572D01*
X433293Y-782639D01*
Y-783705D01*
X433093Y-784772D01*
X432693Y-785705D01*
X432093Y-786505D01*
X431393Y-787039D01*
X430593Y-787172D01*
G01X436293D02*
Y-779172D01*
X440893Y-787172D01*
Y-779172D01*
G01X444093D02*
X446593Y-787172D01*
X449093Y-779172D01*
G01X456593Y-787172D02*
X452593D01*
Y-779172D01*
X456593D01*
G01X454993Y-783039D02*
X452593D01*
G01X460593Y-787172D02*
Y-779172D01*
X463093D01*
X463893Y-779572D01*
X464393Y-780105D01*
X464593Y-781172D01*
X464393Y-782239D01*
X463793Y-782905D01*
X463093Y-783305D01*
X460593D01*
G01X463093D02*
X464593Y-787172D01*
G01X470593Y-779172D02*
Y-787172D01*
G01X468293Y-779172D02*
X472893D01*
G01X480593Y-787172D02*
X476593D01*
Y-779172D01*
X480593D01*
G01X478993Y-783039D02*
X476593D01*
G01X484593Y-787172D02*
Y-779172D01*
X487093D01*
X487893Y-779572D01*
X488393Y-780105D01*
X488593Y-781172D01*
X488393Y-782239D01*
X487793Y-782905D01*
X487093Y-783305D01*
X484593D01*
G01X487093D02*
X488593Y-787172D01*
G01X425093Y-840172D02*
Y-832172D01*
X423893Y-833772D01*
G01Y-840172D02*
X426293D01*
G01X431193Y-836839D02*
X431893Y-835905D01*
X432493Y-835372D01*
X433293Y-835105D01*
X433993Y-835372D01*
X434493Y-835905D01*
X434893Y-836705D01*
X434993Y-837639D01*
X434893Y-838439D01*
X434493Y-839239D01*
X433893Y-839905D01*
X433193Y-840172D01*
X432393Y-839905D01*
X431693Y-839106D01*
X431293Y-837905D01*
X431193Y-836572D01*
X431393Y-834839D01*
X431693Y-833905D01*
X432193Y-832972D01*
X432893Y-832305D01*
X433593Y-832172D01*
X434293Y-832439D01*
X434793Y-833105D01*
G01X441093Y-840439D02*
X440893Y-840305D01*
Y-840039D01*
X441093Y-839905D01*
X441293Y-840039D01*
Y-840305D01*
X441093Y-840439D01*
G01X447193Y-836839D02*
X447893Y-835905D01*
X448493Y-835372D01*
X449293Y-835105D01*
X449993Y-835372D01*
X450493Y-835905D01*
X450893Y-836705D01*
X450993Y-837639D01*
X450893Y-838439D01*
X450493Y-839239D01*
X449893Y-839905D01*
X449193Y-840172D01*
X448393Y-839905D01*
X447693Y-839106D01*
X447293Y-837905D01*
X447193Y-836572D01*
X447393Y-834839D01*
X447693Y-833905D01*
X448193Y-832972D01*
X448893Y-832305D01*
X449593Y-832172D01*
X450293Y-832439D01*
X450793Y-833105D01*
G01X470093Y-840172D02*
Y-832172D01*
X468893Y-833772D01*
G01Y-840172D02*
X471293D01*
G01X477893D02*
X478093Y-838439D01*
X478393Y-836972D01*
X478793Y-835639D01*
X479293Y-834172D01*
X480093Y-832172D01*
X476093D01*
G01X486093Y-840439D02*
X485893Y-840305D01*
Y-840039D01*
X486093Y-839905D01*
X486293Y-840039D01*
Y-840305D01*
X486093Y-840439D01*
G01X492193Y-833505D02*
X492793Y-832705D01*
X493493Y-832305D01*
X494293Y-832172D01*
X495293Y-832439D01*
X495993Y-833105D01*
X496193Y-833905D01*
X496093Y-834706D01*
X495693Y-835372D01*
X493693Y-836705D01*
X492793Y-837639D01*
X492193Y-838972D01*
X491993Y-840172D01*
X496193D01*
G01X490193Y-815172D02*
Y-807172D01*
X493993D01*
G01X492593Y-811039D02*
X490193D01*
G54D49*
G01X808848Y270009D02*
X808500Y270357D01*
Y272925D01*
G01X850500Y360075D02*
Y362620D01*
G01X927000Y361075D02*
Y364363D01*
M02*
